%FSTAX23Y23*%
%MOIN*%
%SFA1B1*%

%IPPOS*%
%ADD143C,0.120000*%
%ADD150C,0.250000*%
%ADD159C,0.061020*%
%ADD161C,0.075000*%
%ADD162C,0.098430*%
%ADD163O,0.088580X0.177170*%
%ADD164O,0.177170X0.088580*%
%ADD171C,0.016000*%
%ADD172C,0.200000*%
%LNgrandmaster-1*%
%LPD*%
G36*
X07082Y04353D02*
Y00505D01*
X03109*
Y00225*
X02289*
Y0031*
X02257Y00342*
X02229*
X02197Y0031*
Y00225*
X01776*
Y00352*
X01781Y00353*
X01782Y00352*
X01782Y00348*
X01786Y00343*
X01791Y00339*
X01797Y00338*
X01804Y00339*
X01809Y00343*
X01812Y00348*
X01814Y00355*
X01812Y00361*
X01809Y00366*
X01804Y0037*
X01797Y00371*
X01791Y0037*
X01786Y00366*
X01782Y00361*
X01782Y00357*
X01781Y00357*
X01776Y00357*
Y00465*
X0173Y00511*
X01658*
X01613Y00466*
Y00312*
X01316*
Y00508*
X00576*
Y00184*
X00002*
Y04349*
X00006Y04353*
X07082*
G37*
%LNgrandmaster-2*%
%LPC*%
G36*
X0257Y04299D02*
X02564Y04298D01*
X02559Y04294*
X02555Y04289*
X02554Y04283*
X02555Y04276*
X02559Y04271*
X02564Y04267*
X0257Y04266*
X02577Y04267*
X02582Y04271*
X02585Y04276*
X02587Y04283*
X02585Y04289*
X02582Y04294*
X02577Y04298*
X0257Y04299*
G37*
G36*
X01294Y04272D02*
X01288Y04271D01*
X01283Y04267*
X01279Y04262*
X01278Y04256*
X01279Y04249*
X01283Y04244*
X01288Y0424*
X01294Y04239*
X01301Y0424*
X01306Y04244*
X01309Y04249*
X01311Y04256*
X01309Y04262*
X01306Y04267*
X01301Y04271*
X01294Y04272*
G37*
G36*
X02078Y04293D02*
X02007D01*
Y04222*
X02078*
Y04293*
G37*
G36*
X01493Y04289D02*
X01422D01*
Y04218*
X01493*
Y04289*
G37*
G36*
X01557Y04245D02*
X01551Y04244D01*
X01546Y0424*
X01542Y04235*
X01541Y04229*
X01542Y04222*
X01546Y04217*
X01551Y04213*
X01557Y04212*
X01564Y04213*
X01569Y04217*
X01572Y04222*
X01574Y04229*
X01572Y04235*
X01569Y0424*
X01564Y04244*
X01557Y04245*
G37*
G36*
X01345Y04191D02*
X01339Y0419D01*
X01333Y04186*
X0133Y04181*
X01329Y04175*
X0133Y04168*
X01333Y04163*
X01339Y0416*
X01345Y04158*
X01351Y0416*
X01357Y04163*
X0136Y04168*
X01361Y04175*
X0136Y04181*
X01357Y04186*
X01351Y0419*
X01345Y04191*
G37*
G36*
X01569Y04187D02*
X01563Y04186D01*
X01558Y04182*
X01554Y04177*
X01553Y04171*
X01554Y04165*
X01558Y04159*
X01563Y04156*
X01569Y04154*
X01576Y04156*
X01581Y04159*
X01584Y04165*
X01586Y04171*
X01584Y04177*
X01581Y04182*
X01576Y04186*
X01569Y04187*
G37*
G36*
X01779Y04172D02*
X01773Y04171D01*
X01768Y04167*
X01764Y04162*
X01763Y04156*
X01764Y04149*
X01768Y04144*
X01773Y0414*
X01779Y04139*
X01786Y0414*
X01791Y04144*
X01794Y04149*
X01796Y04156*
X01794Y04162*
X01791Y04167*
X01786Y04171*
X01779Y04172*
G37*
G36*
X02043Y04193D02*
X02034Y04192D01*
X02025Y04188*
X02017Y04183*
X02012Y04175*
X02008Y04167*
X02007Y04157*
X02008Y04148*
X02012Y04139*
X02017Y04132*
X02025Y04126*
X02034Y04123*
X02043Y04122*
X02052Y04123*
X02061Y04126*
X02068Y04132*
X02074Y04139*
X02077Y04148*
X02079Y04157*
X02077Y04167*
X02074Y04175*
X02068Y04183*
X02061Y04188*
X02052Y04192*
X02043Y04193*
G37*
G36*
X01457Y04189D02*
X01448Y04188D01*
X01439Y04184*
X01432Y04179*
X01426Y04171*
X01423Y04163*
X01421Y04153*
X01423Y04144*
X01426Y04136*
X01432Y04128*
X01439Y04122*
X01448Y04119*
X01457Y04118*
X01466Y04119*
X01475Y04122*
X01483Y04128*
X01488Y04136*
X01492Y04144*
X01493Y04153*
X01492Y04163*
X01488Y04171*
X01483Y04179*
X01475Y04184*
X01466Y04188*
X01457Y04189*
G37*
G36*
X03958Y04152D02*
X03951Y04151D01*
X03945Y04148*
X03939Y04144*
X03935Y04139*
X03933Y04132*
X03932Y04126*
X03933Y04119*
X03935Y04113*
X03939Y04107*
X03945Y04103*
X03951Y04101*
X03958Y041*
X03964Y04101*
X03971Y04103*
X03976Y04107*
X0398Y04113*
X03983Y04119*
X03984Y04126*
X03983Y04132*
X0398Y04139*
X03976Y04144*
X03971Y04148*
X03964Y04151*
X03958Y04152*
G37*
G36*
X03784D02*
X03778Y04151D01*
X03771Y04148*
X03766Y04144*
X03762Y04139*
X03759Y04132*
X03758Y04126*
X03759Y04119*
X03762Y04113*
X03766Y04107*
X03771Y04103*
X03778Y04101*
X03784Y041*
X03791Y04101*
X03797Y04103*
X03803Y04107*
X03807Y04113*
X03809Y04119*
X0381Y04126*
X03809Y04132*
X03807Y04139*
X03803Y04144*
X03797Y04148*
X03791Y04151*
X03784Y04152*
G37*
G36*
X04754Y04132D02*
X04748Y04131D01*
X04743Y04127*
X04739Y04122*
X04738Y04115*
X04739Y04109*
X04743Y04104*
X04748Y041*
X04754Y04099*
X0476Y041*
X04766Y04104*
X04769Y04109*
X04771Y04115*
X04769Y04122*
X04766Y04127*
X0476Y04131*
X04754Y04132*
G37*
G36*
X02146Y0412D02*
X02139Y04118D01*
X02134Y04115*
X02131Y0411*
X02129Y04103*
X02131Y04097*
X02134Y04092*
X02139Y04088*
X02146Y04087*
X02152Y04088*
X02157Y04092*
X02161Y04097*
X02162Y04103*
X02161Y0411*
X02157Y04115*
X02152Y04118*
X02146Y0412*
G37*
G36*
X00285Y04223D02*
X00271Y04221D01*
X00258Y04217*
X00246Y04211*
X00235Y04202*
X00226Y04191*
X00219Y04179*
X00215Y04165*
X00214Y04152*
X00215Y04138*
X00219Y04124*
X00226Y04112*
X00235Y04101*
X00246Y04093*
X00258Y04086*
X00271Y04082*
X00285Y04081*
X00299Y04082*
X00312Y04086*
X00324Y04093*
X00335Y04101*
X00344Y04112*
X0035Y04124*
X00355Y04138*
X00356Y04152*
X00355Y04165*
X0035Y04179*
X00344Y04191*
X00335Y04202*
X00324Y04211*
X00312Y04217*
X00299Y04221*
X00285Y04223*
G37*
G36*
X05267Y04105D02*
X0526Y04103D01*
X05255Y041*
X05251Y04095*
X0525Y04088*
X05251Y04082*
X05255Y04077*
X0526Y04073*
X05267Y04072*
X05273Y04073*
X05278Y04077*
X05282Y04082*
X05283Y04088*
X05282Y04095*
X05278Y041*
X05273Y04103*
X05267Y04105*
G37*
G36*
X02253Y04102D02*
X02247Y04101D01*
X02242Y04098*
X02238Y04092*
X02237Y04086*
X02238Y0408*
X02242Y04075*
X02247Y04071*
X02253Y0407*
X0226Y04071*
X02265Y04075*
X02269Y0408*
X0227Y04086*
X02269Y04092*
X02265Y04098*
X0226Y04101*
X02253Y04102*
G37*
G36*
X03504Y04102D02*
X03498Y04101D01*
X03493Y04097*
X03489Y04092*
X03488Y04086*
X03489Y04079*
X03493Y04074*
X03498Y0407*
X03504Y04069*
X03511Y0407*
X03516Y04074*
X03519Y04079*
X03521Y04086*
X03519Y04092*
X03516Y04097*
X03511Y04101*
X03504Y04102*
G37*
G36*
X03294Y04127D02*
X03284Y04126D01*
X03274Y04121*
X03265Y04115*
X03259Y04106*
X03254Y04096*
X03253Y04086*
X03254Y04075*
X03259Y04065*
X03265Y04056*
X03274Y0405*
X03284Y04046*
X03294Y04044*
X03305Y04046*
X03315Y0405*
X03324Y04056*
X0333Y04065*
X03334Y04075*
X03336Y04086*
X03334Y04096*
X0333Y04106*
X03324Y04115*
X03315Y04121*
X03305Y04126*
X03294Y04127*
G37*
G36*
X02994D02*
X02984Y04126D01*
X02974Y04121*
X02965Y04115*
X02959Y04106*
X02954Y04096*
X02953Y04086*
X02954Y04075*
X02959Y04065*
X02965Y04056*
X02974Y0405*
X02984Y04046*
X02994Y04044*
X03005Y04046*
X03015Y0405*
X03024Y04056*
X0303Y04065*
X03034Y04075*
X03036Y04086*
X03034Y04096*
X0303Y04106*
X03024Y04115*
X03015Y04121*
X03005Y04126*
X02994Y04127*
G37*
G36*
X069Y0416D02*
X06887Y04159D01*
X06874Y04155*
X06862Y04149*
X06852Y04141*
X06844Y0413*
X06837Y04119*
X06834Y04106*
X06832Y04093*
X06834Y0408*
X06837Y04067*
X06844Y04056*
X06852Y04045*
X06862Y04037*
X06874Y04031*
X06887Y04027*
X069Y04026*
X06913Y04027*
X06925Y04031*
X06937Y04037*
X06947Y04045*
X06956Y04056*
X06962Y04067*
X06966Y0408*
X06967Y04093*
X06966Y04106*
X06962Y04119*
X06956Y0413*
X06947Y04141*
X06937Y04149*
X06925Y04155*
X06913Y04159*
X069Y0416*
G37*
G36*
X06569D02*
X06556Y04159D01*
X06543Y04155*
X06532Y04149*
X06521Y04141*
X06513Y0413*
X06507Y04119*
X06503Y04106*
X06502Y04093*
X06503Y0408*
X06507Y04067*
X06513Y04056*
X06521Y04045*
X06532Y04037*
X06543Y04031*
X06556Y04027*
X06569Y04026*
X06582Y04027*
X06595Y04031*
X06606Y04037*
X06617Y04045*
X06625Y04056*
X06631Y04067*
X06635Y0408*
X06636Y04093*
X06635Y04106*
X06631Y04119*
X06625Y0413*
X06617Y04141*
X06606Y04149*
X06595Y04155*
X06582Y04159*
X06569Y0416*
G37*
G36*
X02043Y04093D02*
X02034Y04092D01*
X02025Y04088*
X02017Y04083*
X02012Y04075*
X02008Y04067*
X02007Y04057*
X02008Y04048*
X02012Y04039*
X02017Y04032*
X02025Y04026*
X02034Y04023*
X02043Y04022*
X02052Y04023*
X02061Y04026*
X02068Y04032*
X02074Y04039*
X02077Y04048*
X02079Y04057*
X02077Y04067*
X02074Y04075*
X02068Y04083*
X02061Y04088*
X02052Y04092*
X02043Y04093*
G37*
G36*
X01457Y04089D02*
X01448Y04088D01*
X01439Y04084*
X01432Y04079*
X01426Y04071*
X01423Y04063*
X01421Y04053*
X01423Y04044*
X01426Y04036*
X01432Y04028*
X01439Y04022*
X01448Y04019*
X01457Y04018*
X01466Y04019*
X01475Y04022*
X01483Y04028*
X01488Y04036*
X01492Y04044*
X01493Y04053*
X01492Y04063*
X01488Y04071*
X01483Y04079*
X01475Y04084*
X01466Y04088*
X01457Y04089*
G37*
G36*
X01903Y04034D02*
X01897Y04033D01*
X01892Y04029*
X01888Y04024*
X01887Y04018*
X01888Y04011*
X01892Y04006*
X01897Y04002*
X01903Y04001*
X0191Y04002*
X01915Y04006*
X01918Y04011*
X0192Y04018*
X01918Y04024*
X01915Y04029*
X0191Y04033*
X01903Y04034*
G37*
G36*
X02353Y04034D02*
X02347Y04032D01*
X02341Y04029*
X02338Y04023*
X02337Y04017*
X02338Y04011*
X02341Y04006*
X02347Y04002*
X02353Y04001*
X02359Y04002*
X02364Y04006*
X02368Y04011*
X02369Y04017*
X02368Y04023*
X02364Y04029*
X02359Y04032*
X02353Y04034*
G37*
G36*
X05723Y04083D02*
X05708Y04081D01*
X05694Y04075*
X05682Y04066*
X05673Y04054*
X05667Y0404*
X05665Y04025*
X05667Y0401*
X05673Y03996*
X05682Y03984*
X05694Y03975*
X05708Y03969*
X05723Y03967*
X05738Y03969*
X05752Y03975*
X05764Y03984*
X05773Y03996*
X05779Y0401*
X05781Y04025*
X05779Y0404*
X05773Y04054*
X05764Y04066*
X05752Y04075*
X05738Y04081*
X05723Y04083*
G37*
G36*
X01408Y03996D02*
X01402Y03995D01*
X01396Y03991*
X01393Y03986*
X01392Y0398*
X01393Y03974*
X01396Y03968*
X01402Y03965*
X01408Y03964*
X01414Y03965*
X0142Y03968*
X01423Y03974*
X01424Y0398*
X01423Y03986*
X0142Y03991*
X01414Y03995*
X01408Y03996*
G37*
G36*
X02084Y03912D02*
X02078Y03911D01*
X02073Y03907*
X02069Y03902*
X02068Y03896*
X02069Y03889*
X02069Y03889*
X02066Y03885*
X02066Y03886*
X02059Y03887*
X02053Y03886*
X02048Y03882*
X02044Y03877*
X02043Y03871*
X02044Y03864*
X02048Y03859*
X02053Y03855*
X02059Y03854*
X02066Y03855*
X02071Y03859*
X02074Y03864*
X02076Y03871*
X02074Y03877*
X02074Y03877*
X02078Y03881*
X02078Y0388*
X02084Y03879*
X02091Y0388*
X02096Y03884*
X02099Y03889*
X02101Y03896*
X02099Y03902*
X02096Y03907*
X02091Y03911*
X02084Y03912*
G37*
G36*
X02029Y03852D02*
X02023Y03851D01*
X02018Y03847*
X02014Y03842*
X02013Y03836*
X02013Y03835*
X02013Y03834*
X02009Y03831*
X02004Y03832*
X01998Y03831*
X01993Y03827*
X01989Y03822*
X01988Y03816*
X01989Y03809*
X01993Y03804*
X01998Y038*
X02004Y03799*
X02011Y038*
X02016Y03804*
X02019Y03809*
X02021Y03816*
X02021Y03816*
X02021Y03817*
X02025Y0382*
X02029Y03819*
X02036Y0382*
X02041Y03824*
X02044Y03829*
X02046Y03836*
X02044Y03842*
X02041Y03847*
X02036Y03851*
X02029Y03852*
G37*
G36*
X03699D02*
X03693Y03851D01*
X03688Y03847*
X03684Y03842*
X03683Y03836*
X03684Y03829*
X03688Y03824*
X03693Y0382*
X03699Y03819*
X03706Y0382*
X03711Y03824*
X03714Y03829*
X03716Y03836*
X03714Y03842*
X03711Y03847*
X03706Y03851*
X03699Y03852*
G37*
G36*
X03014Y03847D02*
X03008Y03846D01*
X03003Y03842*
X02999Y03837*
X02998Y03831*
X02999Y03824*
X03003Y03819*
X03008Y03815*
X03014Y03814*
X03021Y03815*
X03026Y03819*
X03029Y03824*
X03031Y03831*
X03029Y03837*
X03026Y03842*
X03021Y03846*
X03014Y03847*
G37*
G36*
X03829Y03822D02*
X03823Y03821D01*
X03818Y03817*
X03814Y03812*
X03813Y03806*
X03814Y03799*
X03818Y03794*
X03823Y0379*
X03829Y03789*
X03836Y0379*
X03841Y03794*
X03844Y03799*
X03846Y03806*
X03844Y03812*
X03841Y03817*
X03836Y03821*
X03829Y03822*
G37*
G36*
X03539D02*
X03533Y03821D01*
X03528Y03817*
X03524Y03812*
X03523Y03806*
X03524Y03799*
X03528Y03794*
X03533Y0379*
X03539Y03789*
X03546Y0379*
X03551Y03794*
X03554Y03799*
X03556Y03806*
X03554Y03812*
X03551Y03817*
X03546Y03821*
X03539Y03822*
G37*
G36*
X03219D02*
X03213Y03821D01*
X03208Y03817*
X03204Y03812*
X03203Y03806*
X03204Y03799*
X03208Y03794*
X03213Y0379*
X03219Y03789*
X03226Y0379*
X03231Y03794*
X03234Y03799*
X03236Y03806*
X03234Y03812*
X03231Y03817*
X03226Y03821*
X03219Y03822*
G37*
G36*
X05723Y03902D02*
X05708Y039D01*
X05694Y03894*
X05682Y03885*
X05673Y03873*
X05667Y03859*
X05665Y03844*
X05667Y03829*
X05673Y03815*
X05682Y03803*
X05694Y03794*
X05708Y03788*
X05723Y03786*
X05738Y03788*
X05752Y03794*
X05764Y03803*
X05773Y03815*
X05779Y03829*
X05781Y03844*
X05779Y03859*
X05773Y03873*
X05764Y03885*
X05752Y03894*
X05738Y039*
X05723Y03902*
G37*
G36*
X02722Y03802D02*
X02716Y03801D01*
X0271Y03797*
X02707Y03792*
X02706Y03786*
X02707Y03779*
X0271Y03774*
X02716Y03771*
X02722Y03769*
X02728Y03771*
X02733Y03774*
X02737Y03779*
X02738Y03786*
X02737Y03792*
X02733Y03797*
X02728Y03801*
X02722Y03802*
G37*
G36*
X06169Y03877D02*
X0607D01*
X06055Y03875*
X06041Y03869*
X06029Y0386*
X0602Y03848*
X06014Y03834*
X06012Y03819*
X06014Y03804*
X0602Y0379*
X06029Y03779*
X06041Y03769*
X06055Y03764*
X0607Y03762*
X06169*
X06183Y03764*
X06197Y03769*
X06209Y03779*
X06219Y0379*
X06224Y03804*
X06226Y03819*
X06224Y03834*
X06219Y03848*
X06209Y0386*
X06197Y03869*
X06183Y03875*
X06169Y03877*
G37*
G36*
X04254Y03792D02*
X04248Y03791D01*
X04243Y03787*
X04239Y03782*
X04238Y03776*
X04239Y03769*
X04243Y03764*
X04248Y0376*
X04254Y03759*
X04261Y0376*
X04266Y03764*
X04269Y03769*
X04271Y03776*
X04269Y03782*
X04266Y03787*
X04261Y03791*
X04254Y03792*
G37*
G36*
X069Y03863D02*
X06885Y03861D01*
X06871Y03856*
X06859Y03846*
X0685Y03834*
X06844Y03821*
X06842Y03806*
X06844Y03791*
X0685Y03777*
X06859Y03765*
X06871Y03756*
X06885Y0375*
X069Y03748*
X06915Y0375*
X06929Y03756*
X06941Y03765*
X0695Y03777*
X06955Y03791*
X06957Y03806*
X06955Y03821*
X0695Y03834*
X06941Y03846*
X06929Y03856*
X06915Y03861*
X069Y03863*
G37*
G36*
X06734D02*
X06719Y03861D01*
X06705Y03856*
X06694Y03846*
X06684Y03834*
X06679Y03821*
X06677Y03806*
X06679Y03791*
X06684Y03777*
X06694Y03765*
X06705Y03756*
X06719Y0375*
X06734Y03748*
X06749Y0375*
X06763Y03756*
X06775Y03765*
X06784Y03777*
X0679Y03791*
X06792Y03806*
X0679Y03821*
X06784Y03834*
X06775Y03846*
X06763Y03856*
X06749Y03861*
X06734Y03863*
G37*
G36*
X06569D02*
X06554Y03861D01*
X0654Y03856*
X06528Y03846*
X06519Y03834*
X06513Y03821*
X06511Y03806*
X06513Y03791*
X06519Y03777*
X06528Y03765*
X0654Y03756*
X06554Y0375*
X06569Y03748*
X06584Y0375*
X06598Y03756*
X0661Y03765*
X06619Y03777*
X06625Y03791*
X06627Y03806*
X06625Y03821*
X06619Y03834*
X0661Y03846*
X06598Y03856*
X06584Y03861*
X06569Y03863*
G37*
G36*
X03699Y03767D02*
X03693Y03766D01*
X03688Y03762*
X03684Y03757*
X03683Y03751*
X03684Y03744*
X03688Y03739*
X03693Y03735*
X03699Y03734*
X03706Y03735*
X03711Y03739*
X03714Y03744*
X03716Y03751*
X03714Y03757*
X03711Y03762*
X03706Y03766*
X03699Y03767*
G37*
G36*
X02993D02*
X02987Y03766D01*
X02981Y03762*
X02978Y03757*
X02977Y03751*
X02978Y03744*
X02981Y03739*
X02987Y03735*
X02993Y03734*
X02999Y03735*
X03004Y03739*
X03008Y03744*
X03009Y03751*
X03008Y03757*
X03004Y03762*
X02999Y03766*
X02993Y03767*
G37*
G36*
X06294Y03717D02*
X06288Y03716D01*
X06283Y03712*
X06279Y03707*
X06278Y03701*
X06279Y03694*
X06283Y03689*
X06288Y03685*
X06294Y03684*
X06301Y03685*
X06306Y03689*
X06309Y03694*
X06311Y03701*
X06309Y03707*
X06306Y03712*
X06301Y03716*
X06294Y03717*
G37*
G36*
X01849D02*
X01843Y03716D01*
X01838Y03712*
X01834Y03707*
X01833Y03701*
X01834Y03694*
X01838Y03689*
X01843Y03685*
X01849Y03684*
X01856Y03685*
X01861Y03689*
X01864Y03694*
X01866Y03701*
X01864Y03707*
X01861Y03712*
X01856Y03716*
X01849Y03717*
G37*
G36*
X04049Y03681D02*
X04043Y0368D01*
X04038Y03676*
X04034Y03671*
X04033Y03665*
X04034Y03658*
X04038Y03653*
X04043Y03649*
X04049Y03648*
X04056Y03649*
X04061Y03653*
X04064Y03658*
X04066Y03665*
X04064Y03671*
X04061Y03676*
X04056Y0368*
X04049Y03681*
G37*
G36*
X02679Y03677D02*
X02673Y03676D01*
X02668Y03672*
X02664Y03667*
X02663Y03661*
X02664Y03654*
X02668Y03649*
X02673Y03645*
X02679Y03644*
X02686Y03645*
X02691Y03649*
X02694Y03654*
X02696Y03661*
X02694Y03667*
X02691Y03672*
X02686Y03676*
X02679Y03677*
G37*
G36*
X01754D02*
X01748Y03676D01*
X01743Y03672*
X01739Y03667*
X01738Y03661*
X01739Y03654*
X01743Y03649*
X01748Y03645*
X01754Y03644*
X01761Y03645*
X01766Y03649*
X01769Y03654*
X01771Y03661*
X01769Y03667*
X01766Y03672*
X01761Y03676*
X01754Y03677*
G37*
G36*
X03424Y03652D02*
X03418Y03651D01*
X03413Y03647*
X03409Y03642*
X03408Y03636*
X03409Y03629*
X03413Y03624*
X03418Y0362*
X03424Y03619*
X03431Y0362*
X03436Y03624*
X03439Y03629*
X03441Y03636*
X03439Y03642*
X03436Y03647*
X03431Y03651*
X03424Y03652*
G37*
G36*
X02799Y03632D02*
X02793Y03631D01*
X02788Y03627*
X02784Y03622*
X02783Y03616*
X02784Y03609*
X02788Y03604*
X02793Y036*
X02799Y03599*
X02806Y036*
X02811Y03604*
X02814Y03609*
X02816Y03616*
X02814Y03622*
X02811Y03627*
X02806Y03631*
X02799Y03632*
G37*
G36*
X02139Y03627D02*
X02133Y03626D01*
X02128Y03622*
X02124Y03617*
X02123Y03611*
X02124Y03604*
X02128Y03599*
X02133Y03595*
X02139Y03594*
X02146Y03595*
X02151Y03599*
X02154Y03604*
X02156Y03611*
X02154Y03617*
X02151Y03622*
X02146Y03626*
X02139Y03627*
G37*
G36*
X01884Y03617D02*
X01878Y03616D01*
X01873Y03612*
X01869Y03607*
X01868Y03601*
X01869Y03594*
X01873Y03589*
X01878Y03585*
X01884Y03584*
X01891Y03585*
X01896Y03589*
X01899Y03594*
X01901Y03601*
X01899Y03607*
X01896Y03612*
X01891Y03616*
X01884Y03617*
G37*
G36*
X03239Y03612D02*
X03233Y03611D01*
X03228Y03607*
X03224Y03602*
X03223Y03596*
X03224Y03589*
X03228Y03584*
X03233Y0358*
X03239Y03579*
X03246Y0358*
X03251Y03584*
X03254Y03589*
X03256Y03596*
X03254Y03602*
X03251Y03607*
X03246Y03611*
X03239Y03612*
G37*
G36*
X01549Y03637D02*
X01543Y03636D01*
X01538Y03632*
X01534Y03627*
X01533Y03621*
X01534Y03614*
X01538Y03609*
X01543Y03605*
X01549Y03604*
X01556Y03605*
X01556Y03606*
X01559Y03602*
X01559Y03602*
X01558Y03596*
X01559Y03589*
X01563Y03584*
X01568Y0358*
X01574Y03579*
X01581Y0358*
X01586Y03584*
X01589Y03589*
X01591Y03596*
X01589Y03602*
X01586Y03607*
X01581Y03611*
X01574Y03612*
X01568Y03611*
X01568Y0361*
X01564Y03614*
X01564Y03614*
X01566Y03621*
X01564Y03627*
X01561Y03632*
X01556Y03636*
X01549Y03637*
G37*
G36*
X02422Y03624D02*
X02413Y03623D01*
X02405Y03617*
X024Y0361*
X02398Y03601*
X024Y03592*
X02405Y03584*
X02413Y03579*
X02422Y03577*
X02431Y03579*
X02438Y03584*
X02443Y03592*
X02445Y03601*
X02443Y0361*
X02438Y03617*
X02431Y03623*
X02422Y03624*
G37*
G36*
X02774Y03582D02*
X02768Y03581D01*
X02763Y03577*
X02759Y03572*
X02758Y03566*
X02759Y03559*
X02763Y03554*
X02768Y0355*
X02774Y03549*
X02781Y0355*
X02786Y03554*
X02789Y03559*
X02791Y03566*
X02789Y03572*
X02786Y03577*
X02781Y03581*
X02774Y03582*
G37*
G36*
X0144Y03573D02*
X01434Y03572D01*
X01429Y03568*
X01425Y03563*
X01424Y03557*
X01425Y0355*
X01429Y03545*
X01434Y03541*
X0144Y0354*
X01447Y03541*
X01452Y03545*
X01455Y0355*
X01457Y03557*
X01455Y03563*
X01452Y03568*
X01447Y03572*
X0144Y03573*
G37*
G36*
X05994Y03568D02*
X05988Y03567D01*
X05983Y03563*
X05979Y03558*
X05978Y03552*
X05979Y03545*
X05983Y0354*
X05988Y03536*
X05994Y03535*
X06001Y03536*
X06006Y0354*
X06009Y03545*
X06011Y03552*
X06009Y03558*
X06006Y03563*
X06001Y03567*
X05994Y03568*
G37*
G36*
X02434Y03562D02*
X02428Y03561D01*
X02423Y03557*
X02419Y03552*
X02418Y03546*
X02419Y03539*
X02423Y03534*
X02428Y0353*
X02434Y03529*
X02441Y0353*
X02446Y03534*
X02449Y03539*
X02451Y03546*
X02449Y03552*
X02446Y03557*
X02441Y03561*
X02434Y03562*
G37*
G36*
X02254Y03552D02*
X02248Y03551D01*
X02243Y03547*
X02239Y03542*
X02238Y03536*
X02239Y03529*
X02242Y03525*
X02239Y03521*
X02234Y03522*
X02228Y03521*
X02223Y03517*
X02219Y03512*
X02218Y03506*
X02219Y03499*
X02223Y03494*
X02228Y0349*
X02234Y03489*
X02241Y0349*
X02246Y03494*
X02249Y03499*
X02251Y03506*
X02249Y03512*
X02247Y03516*
X0225Y0352*
X02254Y03519*
X02261Y0352*
X02266Y03524*
X02269Y03529*
X02271Y03536*
X02269Y03542*
X02266Y03547*
X02261Y03551*
X02254Y03552*
G37*
G36*
X05274Y03527D02*
X05268Y03526D01*
X05263Y03522*
X05259Y03517*
X05258Y03511*
X05259Y03504*
X05263Y03499*
X05268Y03495*
X05274Y03494*
X05281Y03495*
X05286Y03499*
X05289Y03504*
X05291Y03511*
X05289Y03517*
X05286Y03522*
X05281Y03526*
X05274Y03527*
G37*
G36*
X03622Y03502D02*
X03616Y03501D01*
X03611Y03497*
X03607Y03492*
X03606Y03486*
X03607Y03479*
X03611Y03474*
X03616Y0347*
X03622Y03469*
X03629Y0347*
X03634Y03474*
X03637Y03479*
X03639Y03486*
X03637Y03492*
X03634Y03497*
X03629Y03501*
X03622Y03502*
G37*
G36*
X02579D02*
X02573Y03501D01*
X02568Y03497*
X02564Y03492*
X02563Y03486*
X02564Y03479*
X02568Y03474*
X02573Y0347*
X02579Y03469*
X02586Y0347*
X02591Y03474*
X02594Y03479*
X02596Y03486*
X02594Y03492*
X02591Y03497*
X02586Y03501*
X02579Y03502*
G37*
G36*
X03529Y03497D02*
X03523Y03496D01*
X03518Y03492*
X03514Y03487*
X03513Y03481*
X03514Y03474*
X03518Y03469*
X03523Y03465*
X03529Y03464*
X03536Y03465*
X03541Y03469*
X03544Y03474*
X03546Y03481*
X03544Y03487*
X03541Y03492*
X03536Y03496*
X03529Y03497*
G37*
G36*
X02389D02*
X02383Y03496D01*
X02378Y03492*
X02374Y03487*
X02373Y03481*
X02374Y03474*
X02378Y03469*
X02383Y03465*
X02389Y03464*
X02396Y03465*
X02401Y03469*
X02404Y03474*
X02406Y03481*
X02404Y03487*
X02401Y03492*
X02396Y03496*
X02389Y03497*
G37*
G36*
X06509Y03472D02*
X06503Y03471D01*
X06498Y03467*
X06494Y03462*
X06493Y03456*
X06494Y03449*
X06498Y03444*
X06503Y0344*
X06509Y03439*
X06516Y0344*
X06521Y03444*
X06524Y03449*
X06526Y03456*
X06524Y03462*
X06521Y03467*
X06516Y03471*
X06509Y03472*
G37*
G36*
X03436Y03473D02*
X0343Y03472D01*
X03425Y03468*
X03421Y03463*
X0342Y03457*
X03421Y0345*
X03425Y03445*
X0343Y03441*
X03436Y0344*
X03443Y03441*
X03448Y03445*
X0345Y03448*
X0345Y03448*
X03456Y03447*
X03458Y03444*
X03463Y0344*
X03469Y03439*
X03476Y0344*
X03481Y03444*
X03484Y03449*
X03486Y03456*
X03484Y03462*
X03481Y03467*
X03476Y03471*
X03469Y03472*
X03463Y03471*
X03458Y03467*
X03456Y03464*
X03456Y03464*
X0345Y03465*
X03448Y03468*
X03443Y03472*
X03436Y03473*
G37*
G36*
X03358Y03464D02*
X03352Y03463D01*
X03347Y03459*
X03343Y03454*
X03342Y03448*
X03343Y03441*
X03347Y03436*
X03352Y03432*
X03358Y03431*
X03365Y03432*
X0337Y03436*
X03373Y03441*
X03374Y03443*
X03379*
X03379Y0344*
X03383Y03435*
X03388Y03431*
X03394Y0343*
X03401Y03431*
X03406Y03435*
X03409Y0344*
X03411Y03447*
X03409Y03453*
X03406Y03458*
X03401Y03462*
X03394Y03463*
X03388Y03462*
X03383Y03458*
X03379Y03453*
X03379Y03451*
X03374*
X03373Y03454*
X0337Y03459*
X03365Y03463*
X03358Y03464*
G37*
G36*
X02422Y03467D02*
X02413Y03465D01*
X02405Y0346*
X024Y03452*
X02398Y03443*
X024Y03434*
X02405Y03427*
X02413Y03422*
X02422Y0342*
X02431Y03422*
X02438Y03427*
X02443Y03434*
X02445Y03443*
X02443Y03452*
X02438Y0346*
X02431Y03465*
X02422Y03467*
G37*
G36*
X06479Y03442D02*
X06473Y03441D01*
X06468Y03437*
X06464Y03432*
X06463Y03426*
X06464Y03419*
X06468Y03414*
X06473Y0341*
X06479Y03409*
X06486Y0341*
X06491Y03414*
X06494Y03419*
X06496Y03426*
X06494Y03432*
X06491Y03437*
X06486Y03441*
X06479Y03442*
G37*
G36*
X02634Y03422D02*
X02628Y03421D01*
X02623Y03417*
X02619Y03412*
X02618Y03406*
X02619Y03399*
X02623Y03394*
X02628Y0339*
X02634Y03389*
X02641Y0339*
X02646Y03394*
X02649Y03399*
X02651Y03406*
X02649Y03412*
X02646Y03417*
X02641Y03421*
X02634Y03422*
G37*
G36*
X06447Y03412D02*
X06441Y03411D01*
X06436Y03407*
X06432Y03402*
X06431Y03396*
X06432Y03389*
X06436Y03384*
X06441Y0338*
X06447Y03379*
X06453Y0338*
X06459Y03384*
X06462Y03389*
X06463Y03396*
X06462Y03402*
X06459Y03407*
X06453Y03411*
X06447Y03412*
G37*
G36*
X03068Y03411D02*
X03062Y0341D01*
X03057Y03407*
X03053Y03401*
X03052Y03395*
X03053Y03389*
X03057Y03384*
X03062Y0338*
X03068Y03379*
X03075Y0338*
X0308Y03384*
X03083Y03389*
X03085Y03395*
X03083Y03401*
X0308Y03407*
X03075Y0341*
X03068Y03411*
G37*
G36*
X06409Y03387D02*
X06403Y03386D01*
X06398Y03382*
X06394Y03377*
X06393Y03371*
X06394Y03364*
X06398Y03359*
X06403Y03355*
X06409Y03354*
X06416Y03355*
X06421Y03359*
X06424Y03364*
X06426Y03371*
X06424Y03377*
X06421Y03382*
X06416Y03386*
X06409Y03387*
G37*
G36*
X03302Y0336D02*
X03296Y03359D01*
X03291Y03355*
X03287Y0335*
X03286Y03344*
X03287Y03337*
X03291Y03332*
X03296Y03328*
X03302Y03327*
X03309Y03328*
X03314Y03332*
X03317Y03337*
X03319Y03344*
X03317Y0335*
X03314Y03355*
X03309Y03359*
X03302Y0336*
G37*
G36*
X06354Y03347D02*
X06348Y03346D01*
X06343Y03342*
X06339Y03337*
X06338Y03331*
X06339Y03324*
X06343Y03319*
X06348Y03316*
X06354Y03314*
X0636Y03316*
X06366Y03319*
X06369Y03324*
X06371Y03331*
X06369Y03337*
X06366Y03342*
X0636Y03346*
X06354Y03347*
G37*
G36*
X03542Y03335D02*
X03536Y03334D01*
X03531Y0333*
X03527Y03325*
X03526Y03319*
X03527Y03312*
X03531Y03307*
X03536Y03303*
X03542Y03302*
X03549Y03303*
X03554Y03307*
X03557Y03312*
X03559Y03319*
X03557Y03325*
X03554Y0333*
X03549Y03334*
X03542Y03335*
G37*
G36*
X03263Y0332D02*
X03257Y03318D01*
X03252Y03315*
X03248Y0331*
X03247Y03303*
X03248Y03297*
X03252Y03292*
X03257Y03288*
X03263Y03287*
X03269Y03288*
X03275Y03292*
X03278Y03297*
X0328Y03303*
X03278Y0331*
X03275Y03315*
X03269Y03318*
X03263Y0332*
G37*
G36*
X03491Y03313D02*
X03485Y03312D01*
X0348Y03308*
X03476Y03303*
X03475Y03297*
X03476Y0329*
X0348Y03285*
X03485Y03281*
X03491Y0328*
X03498Y03281*
X03503Y03285*
X03506Y0329*
X03508Y03297*
X03506Y03303*
X03503Y03308*
X03498Y03312*
X03491Y03313*
G37*
G36*
X03653Y03309D02*
X03647Y03308D01*
X03642Y03304*
X03638Y03299*
X03637Y03293*
X03638Y03286*
X03642Y03281*
X03647Y03277*
X03653Y03276*
X0366Y03277*
X03665Y03281*
X03668Y03286*
X0367Y03293*
X03668Y03299*
X03665Y03304*
X0366Y03308*
X03653Y03309*
G37*
G36*
X06444Y03307D02*
X06438Y03306D01*
X06433Y03302*
X06429Y03297*
X06428Y03291*
X06429Y03284*
X06433Y03279*
X06438Y03275*
X06444Y03274*
X06451Y03275*
X06456Y03279*
X06459Y03284*
X06461Y03291*
X06459Y03297*
X06456Y03302*
X06451Y03306*
X06444Y03307*
G37*
G36*
X0259Y03304D02*
X02584Y03303D01*
X02579Y03299*
X02575Y03294*
X02574Y03288*
X02575Y03281*
X02579Y03276*
X02584Y03272*
X0259Y03271*
X02597Y03272*
X02602Y03276*
X02605Y03281*
X02607Y03288*
X02605Y03294*
X02602Y03299*
X02597Y03303*
X0259Y03304*
G37*
G36*
X03374Y03289D02*
X03368Y03288D01*
X03363Y03284*
X03359Y03279*
X03358Y03273*
X03359Y03266*
X03363Y03261*
X03368Y03257*
X03374Y03256*
X03381Y03257*
X03386Y03261*
X03389Y03266*
X03391Y03273*
X03389Y03279*
X03386Y03284*
X03381Y03288*
X03374Y03289*
G37*
G36*
X06334Y03282D02*
X06328Y03281D01*
X06323Y03277*
X06319Y03272*
X06318Y03266*
X06319Y03259*
X06323Y03254*
X06328Y0325*
X06334Y03249*
X06341Y0325*
X06346Y03254*
X06349Y03259*
X06351Y03266*
X06349Y03272*
X06346Y03277*
X06341Y03281*
X06334Y03282*
G37*
G36*
X03744Y03277D02*
X03738Y03276D01*
X03733Y03272*
X03729Y03267*
X03728Y03261*
X03729Y03254*
X03733Y03249*
X03738Y03245*
X03744Y03244*
X03751Y03245*
X03756Y03249*
X03759Y03254*
X03761Y03261*
X03759Y03267*
X03756Y03272*
X03751Y03276*
X03744Y03277*
G37*
G36*
X02259D02*
X02253Y03276D01*
X02248Y03272*
X02244Y03267*
X02243Y03261*
X02244Y03254*
X02248Y03249*
X02253Y03245*
X02259Y03244*
X02266Y03245*
X02271Y03249*
X02274Y03254*
X02276Y03261*
X02274Y03267*
X02271Y03272*
X02266Y03276*
X02259Y03277*
G37*
G36*
X0323Y03251D02*
X03224Y0325D01*
X03219Y03246*
X03215Y03241*
X03214Y03235*
X03215Y03228*
X03219Y03223*
X03224Y03219*
X0323Y03218*
X03237Y03219*
X03242Y03223*
X03245Y03228*
X03247Y03235*
X03245Y03241*
X03242Y03246*
X03237Y0325*
X0323Y03251*
G37*
G36*
X06282Y03242D02*
X06276Y03241D01*
X0627Y03237*
X06267Y03232*
X06266Y03226*
X06267Y03219*
X0627Y03214*
X06276Y0321*
X06282Y03209*
X06288Y0321*
X06293Y03214*
X06297Y03219*
X06298Y03226*
X06297Y03232*
X06293Y03237*
X06288Y03241*
X06282Y03242*
G37*
G36*
X03806Y03251D02*
X038Y0325D01*
X03795Y03246*
X03791Y03241*
X0379Y03235*
X03791Y03228*
X03795Y03223*
X03797Y03222*
X03796Y03216*
X03793Y03216*
X03788Y03212*
X03784Y03207*
X03783Y03201*
X03784Y03194*
X03788Y03189*
X03793Y03185*
X03799Y03184*
X03806Y03185*
X03811Y03189*
X03814Y03194*
X03816Y03201*
X03814Y03207*
X03811Y03212*
X03809Y03214*
X0381Y03219*
X03813Y03219*
X03818Y03223*
X03821Y03228*
X03823Y03235*
X03821Y03241*
X03818Y03246*
X03813Y0325*
X03806Y03251*
G37*
G36*
X02205Y03216D02*
X02199Y03215D01*
X02194Y03211*
X0219Y03206*
X02189Y032*
X0219Y03193*
X02194Y03188*
X02199Y03184*
X02205Y03183*
X02212Y03184*
X02217Y03188*
X0222Y03193*
X02222Y032*
X0222Y03206*
X02217Y03211*
X02212Y03215*
X02205Y03216*
G37*
G36*
X02422Y03263D02*
X02413Y03261D01*
X02405Y03256*
X024Y03248*
X02398Y03239*
X024Y0323*
X02405Y03223*
X02409Y0322*
X02408Y03215*
X02407Y03214*
X02402Y03211*
X02398Y03206*
X02397Y03199*
X02398Y03193*
X02402Y03188*
X02407Y03184*
X02414Y03183*
X0242Y03184*
X02425Y03188*
X02429Y03193*
X0243Y03199*
X02429Y03206*
X02425Y03211*
X02425Y03211*
X02426Y03217*
X02431Y03218*
X02438Y03223*
X02443Y0323*
X02445Y03239*
X02443Y03248*
X02438Y03256*
X02431Y03261*
X02422Y03263*
G37*
G36*
X06309Y03215D02*
X06303Y03214D01*
X06297Y0321*
X06294Y03205*
X06293Y03199*
X06294Y03192*
X06297Y03187*
X06303Y03183*
X06309Y03182*
X06315Y03183*
X0632Y03187*
X06324Y03192*
X06325Y03199*
X06324Y03205*
X0632Y0321*
X06315Y03214*
X06309Y03215*
G37*
G36*
X06439Y03207D02*
X06433Y03206D01*
X06428Y03202*
X06424Y03197*
X06423Y03191*
X06424Y03184*
X06428Y03179*
X06433Y03175*
X06439Y03174*
X06446Y03175*
X06451Y03179*
X06454Y03184*
X06456Y03191*
X06454Y03197*
X06451Y03202*
X06446Y03206*
X06439Y03207*
G37*
G36*
X03188Y03203D02*
X03182Y03202D01*
X03177Y03198*
X03173Y03193*
X03172Y03187*
X03173Y0318*
X03177Y03175*
X03182Y03171*
X03188Y0317*
X03195Y03171*
X032Y03175*
X03204Y0318*
X03205Y03187*
X03204Y03193*
X032Y03198*
X03195Y03202*
X03188Y03203*
G37*
G36*
X02591Y03202D02*
X02585Y03201D01*
X0258Y03197*
X02576Y03192*
X02575Y03186*
X02576Y03179*
X0258Y03174*
X02585Y03171*
X02591Y03169*
X02598Y03171*
X02603Y03174*
X02606Y03179*
X02608Y03186*
X02606Y03192*
X02603Y03197*
X02598Y03201*
X02591Y03202*
G37*
G36*
X02462Y03188D02*
X02456Y03187D01*
X0245Y03183*
X02447Y03178*
X02446Y03172*
X02447Y03166*
X0245Y0316*
X02456Y03157*
X02462Y03155*
X02468Y03157*
X02473Y0316*
X02477Y03166*
X02478Y03172*
X02477Y03178*
X02473Y03183*
X02468Y03187*
X02462Y03188*
G37*
G36*
X06339Y03167D02*
X06333Y03166D01*
X06328Y03162*
X06324Y03157*
X06323Y03151*
X06324Y03144*
X06328Y03139*
X06333Y03135*
X06339Y03134*
X06346Y03135*
X06351Y03139*
X06354Y03144*
X06356Y03151*
X06354Y03157*
X06351Y03162*
X06346Y03166*
X06339Y03167*
G37*
G36*
X03829Y03192D02*
X03823Y03191D01*
X03818Y03187*
X03814Y03182*
X03813Y03176*
X03814Y03169*
X03818Y03164*
X03823Y0316*
X03829Y03159*
X03836Y0316*
X03836Y03161*
X03839Y03157*
X03839Y03157*
X03838Y03151*
X03839Y03144*
X03843Y03139*
X03848Y03135*
X03854Y03134*
X03861Y03135*
X03866Y03139*
X03869Y03144*
X03871Y03151*
X03869Y03157*
X03866Y03162*
X03861Y03166*
X03854Y03167*
X03848Y03166*
X03848Y03165*
X03844Y03169*
X03844Y03169*
X03846Y03176*
X03844Y03182*
X03841Y03187*
X03836Y03191*
X03829Y03192*
G37*
G36*
X01459Y03163D02*
X01453Y03162D01*
X01448Y03158*
X01444Y03153*
X01443Y03147*
X01444Y0314*
X01448Y03135*
X01453Y03131*
X01459Y0313*
X01466Y03131*
X01471Y03135*
X01474Y0314*
X01476Y03147*
X01474Y03153*
X01471Y03158*
X01466Y03162*
X01459Y03163*
G37*
G36*
X03275Y03158D02*
X03269Y03156D01*
X03264Y03153*
X0326Y03147*
X03259Y03141*
X0326Y03135*
X03264Y0313*
X03269Y03126*
X03275Y03125*
X03281Y03126*
X03287Y0313*
X0329Y03135*
X03291Y03141*
X0329Y03147*
X03287Y03153*
X03281Y03156*
X03275Y03158*
G37*
G36*
X06304Y03137D02*
X06298Y03136D01*
X06293Y03132*
X06289Y03127*
X06288Y03121*
X06289Y03114*
X06293Y03109*
X06298Y03105*
X06304Y03104*
X06311Y03105*
X06316Y03109*
X06319Y03114*
X06321Y03121*
X06319Y03127*
X06316Y03132*
X06311Y03136*
X06304Y03137*
G37*
G36*
X03939D02*
X03933Y03136D01*
X03928Y03132*
X03924Y03127*
X03923Y03121*
X03924Y03114*
X03928Y03109*
X03933Y03105*
X03939Y03104*
X03946Y03105*
X03951Y03109*
X03954Y03114*
X03956Y03121*
X03954Y03127*
X03951Y03132*
X03946Y03136*
X03939Y03137*
G37*
G36*
X03491Y03119D02*
X03485Y03118D01*
X0348Y03114*
X03476Y03109*
X03475Y03103*
X03476Y03096*
X0348Y03091*
X03485Y03087*
X03491Y03086*
X03498Y03087*
X03503Y03091*
X03506Y03096*
X03508Y03103*
X03506Y03109*
X03503Y03114*
X03498Y03118*
X03491Y03119*
G37*
G36*
X02418Y03134D02*
X02412Y03133D01*
X02407Y0313*
X02403Y03124*
X02402Y03118*
X02403Y03112*
X02407Y03106*
X02408Y03106*
Y031*
X02405Y03098*
X024Y03091*
X02398Y03082*
X024Y03073*
X02405Y03065*
X02413Y0306*
X02422Y03058*
X02431Y0306*
X02438Y03065*
X02443Y03073*
X02445Y03082*
X02443Y03091*
X02438Y03098*
X02432Y03102*
X02431Y03105*
X02431Y03108*
X02433Y03112*
X02435Y03118*
X02433Y03124*
X0243Y0313*
X02424Y03133*
X02418Y03134*
G37*
G36*
X03368Y03066D02*
X03362Y03065D01*
X03357Y03061*
X03353Y03056*
X03352Y0305*
X03353Y03043*
X03357Y03038*
X03362Y03034*
X03368Y03033*
X03375Y03034*
X0338Y03038*
X03383Y03043*
X03385Y0305*
X03383Y03056*
X0338Y03061*
X03375Y03065*
X03368Y03066*
G37*
G36*
X03344Y03012D02*
X03338Y03011D01*
X03333Y03007*
X03329Y03002*
X03328Y02996*
X03329Y02989*
X03333Y02984*
X03338Y0298*
X03344Y02979*
X03351Y0298*
X03356Y02984*
X03359Y02989*
X03361Y02996*
X03359Y03002*
X03356Y03007*
X03351Y03011*
X03344Y03012*
G37*
G36*
X03197Y02986D02*
X03191Y02985D01*
X03186Y02981*
X03182Y02976*
X03181Y0297*
X03182Y02963*
X03186Y02958*
X03191Y02954*
X03197Y02953*
X03204Y02954*
X03209Y02958*
X03212Y02963*
X03214Y0297*
X03212Y02976*
X03209Y02981*
X03204Y02985*
X03197Y02986*
G37*
G36*
X04794Y02824D02*
X04788Y02823D01*
X04782Y02819*
X04779Y02814*
X04777Y02808*
X04779Y02801*
X04782Y02796*
X04788Y02793*
X04794Y02791*
X048Y02793*
X04805Y02796*
X04809Y02801*
X0481Y02808*
X04809Y02814*
X04805Y02819*
X048Y02823*
X04794Y02824*
G37*
G36*
X04503Y02806D02*
X04497Y02804D01*
X04492Y02801*
X04488Y02796*
X04487Y02789*
X04488Y02783*
X04492Y02778*
X04497Y02774*
X04503Y02773*
X04509Y02774*
X04515Y02778*
X04518Y02783*
X04519Y02789*
X04518Y02796*
X04515Y02801*
X04509Y02804*
X04503Y02806*
G37*
G36*
X02146Y02769D02*
X0214Y02768D01*
X02135Y02764*
X02131Y02759*
X0213Y02753*
X02131Y02746*
X02135Y02741*
X0214Y02737*
X02146Y02736*
X02153Y02737*
X02158Y02741*
X02161Y02746*
X02163Y02753*
X02161Y02759*
X02158Y02764*
X02153Y02768*
X02146Y02769*
G37*
G36*
X02692Y02737D02*
X02686Y02736D01*
X02681Y02732*
X02677Y02727*
X02676Y02721*
X02677Y02715*
X02681Y02709*
X02686Y02706*
X02692Y02705*
X02699Y02706*
X02704Y02709*
X02707Y02715*
X02709Y02721*
X02707Y02727*
X02704Y02732*
X02699Y02736*
X02692Y02737*
G37*
G36*
X02394Y02736D02*
X02388Y02735D01*
X02383Y02732*
X02379Y02726*
X02378Y0272*
X02379Y02714*
X02383Y02708*
X02388Y02705*
X02394Y02704*
X024Y02705*
X02406Y02708*
X02409Y02714*
X02411Y0272*
X02409Y02726*
X02406Y02732*
X024Y02735*
X02394Y02736*
G37*
G36*
X02494Y02712D02*
X02488Y02711D01*
X02483Y02707*
X02479Y02702*
X02478Y02696*
X02479Y02689*
X02483Y02684*
X02488Y02681*
X02488Y02679*
Y02678*
X02488Y02675*
X02483Y02672*
X02479Y02667*
X02478Y02661*
X02479Y02654*
X02483Y02649*
X02488Y02645*
X02494Y02644*
X02501Y02645*
X02506Y02649*
X02509Y02654*
X02511Y02661*
X02509Y02667*
X02506Y02672*
X02501Y02675*
X02501Y02678*
Y02679*
X02501Y02681*
X02506Y02684*
X02509Y02689*
X02511Y02696*
X02509Y02702*
X02506Y02707*
X02501Y02711*
X02494Y02712*
G37*
G36*
X02958Y02637D02*
X02952Y02636D01*
X02947Y02632*
X02943Y02627*
X02942Y02621*
X02943Y02614*
X02947Y02609*
X02952Y02605*
X02958Y02604*
X02965Y02605*
X0297Y02609*
X02973Y02614*
X02975Y02621*
X02973Y02627*
X0297Y02632*
X02965Y02636*
X02958Y02637*
G37*
G36*
X02429D02*
X02422Y02636D01*
X02417Y02632*
X02414Y02627*
X02412Y02621*
X02414Y02614*
X02417Y02609*
X02422Y02605*
X02429Y02604*
X02435Y02605*
X0244Y02609*
X02444Y02614*
X02445Y02621*
X02444Y02627*
X0244Y02632*
X02435Y02636*
X02429Y02637*
G37*
G36*
X02252Y02629D02*
X02246Y02628D01*
X0224Y02625*
X02237Y02619*
X02236Y02613*
X02237Y02607*
X02239Y02603*
X02236Y02599*
X02231Y026*
X02225Y02599*
X0222Y02595*
X02216Y0259*
X02215Y02584*
X02216Y02577*
X0222Y02572*
X02225Y02569*
X02231Y02567*
X02237Y02569*
X02243Y02572*
X02246Y02577*
X02248Y02584*
X02246Y0259*
X02244Y02594*
X02247Y02598*
X02252Y02597*
X02258Y02598*
X02263Y02602*
X02267Y02607*
X02268Y02613*
X02267Y02619*
X02263Y02625*
X02258Y02628*
X02252Y02629*
G37*
G36*
X02821Y02617D02*
X02815Y02616D01*
X0281Y02612*
X02806Y02607*
X02805Y02601*
X02806Y02594*
X0281Y02589*
X02815Y02585*
X02821Y02584*
X02828Y02585*
X02833Y02589*
X02836Y02594*
X02838Y02601*
X02836Y02607*
X02833Y02612*
X02828Y02616*
X02821Y02617*
G37*
G36*
X03623Y02603D02*
X03617Y02602D01*
X03612Y02598*
X03608Y02593*
X03607Y02587*
X03608Y0258*
X03612Y02575*
X03617Y02571*
X03623Y0257*
X0363Y02571*
X03635Y02575*
X03638Y0258*
X0364Y02587*
X03638Y02593*
X03635Y02598*
X0363Y02602*
X03623Y02603*
G37*
G36*
X04298Y02641D02*
X04286Y02639D01*
X04275Y02635*
X04266Y02627*
X04258Y02618*
X04254Y02607*
X04252Y02595*
X04254Y02583*
X04258Y02572*
X04266Y02562*
X04275Y02555*
X04286Y02551*
X04298Y02549*
X0431Y02551*
X04321Y02555*
X04331Y02562*
X04338Y02572*
X04342Y02583*
X04344Y02595*
X04342Y02607*
X04338Y02618*
X04331Y02627*
X04321Y02635*
X0431Y02639*
X04298Y02641*
G37*
G36*
X0418D02*
X04168Y02639D01*
X04157Y02635*
X04148Y02627*
X0414Y02618*
X04136Y02607*
X04134Y02595*
X04136Y02583*
X0414Y02572*
X04148Y02562*
X04157Y02555*
X04168Y02551*
X0418Y02549*
X04192Y02551*
X04203Y02555*
X04212Y02562*
X0422Y02572*
X04224Y02583*
X04226Y02595*
X04224Y02607*
X0422Y02618*
X04212Y02627*
X04203Y02635*
X04192Y02639*
X0418Y02641*
G37*
G36*
X04062D02*
X0405Y02639D01*
X04039Y02635*
X04029Y02627*
X04022Y02618*
X04018Y02607*
X04016Y02595*
X04018Y02583*
X04022Y02572*
X04029Y02562*
X04039Y02555*
X0405Y02551*
X04062Y02549*
X04074Y02551*
X04085Y02555*
X04094Y02562*
X04102Y02572*
X04106Y02583*
X04108Y02595*
X04106Y02607*
X04102Y02618*
X04094Y02627*
X04085Y02635*
X04074Y02639*
X04062Y02641*
G37*
G36*
X06284Y02517D02*
X06278Y02516D01*
X06273Y02512*
X06269Y02507*
X06268Y02501*
X06269Y02494*
X06273Y02489*
X06278Y02485*
X06284Y02484*
X06291Y02485*
X06296Y02489*
X06299Y02494*
X06301Y02501*
X06299Y02507*
X06296Y02512*
X06291Y02516*
X06284Y02517*
G37*
G36*
X0102Y02497D02*
X01014Y02496D01*
X01009Y02492*
X01005Y02487*
X01004Y02481*
X01005Y02474*
X01009Y02469*
X01014Y02465*
X0102Y02464*
X01027Y02465*
X01032Y02469*
X01035Y02474*
X01037Y02481*
X01035Y02487*
X01032Y02492*
X01027Y02496*
X0102Y02497*
G37*
G36*
X02624Y02477D02*
X02618Y02476D01*
X02613Y02472*
X02609Y02467*
X02608Y02461*
X02609Y02454*
X02609Y02454*
X02606Y0245*
X02606Y02451*
X02599Y02452*
X02593Y02451*
X02588Y02447*
X02584Y02442*
X02583Y02436*
X02584Y02431*
X02583Y0243*
X02581Y02427*
X0258Y02427*
X02575Y02428*
X02569Y02427*
X02564Y02423*
X0256Y02418*
X02559Y02412*
X0256Y02405*
X02564Y024*
X02569Y02396*
X02575Y02395*
X02582Y02396*
X02587Y024*
X0259Y02405*
X02592Y02412*
X02591Y02416*
X02591Y02417*
X02594Y0242*
X02595Y0242*
X02599Y02419*
X02606Y0242*
X02611Y02424*
X02614Y02429*
X02616Y02436*
X02614Y02442*
X02614Y02442*
X02618Y02446*
X02618Y02445*
X02624Y02444*
X02631Y02445*
X02636Y02449*
X02639Y02454*
X02641Y02461*
X02639Y02467*
X02636Y02472*
X02631Y02476*
X02624Y02477*
G37*
G36*
X02272Y0248D02*
X02265Y02478D01*
X0226Y02475*
X02256Y0247*
X02255Y02463*
X02256Y02457*
X0226Y02452*
X02265Y02448*
X02272Y02447*
X02278Y02448*
X02283Y02452*
X02287Y02457*
X02288Y02463*
X02287Y0247*
X02283Y02475*
X02278Y02478*
X02272Y0248*
G37*
G36*
X02525Y02479D02*
X02519Y02478D01*
X02514Y02474*
X0251Y02469*
X02509Y02463*
X0251Y02456*
X02514Y02451*
X02519Y02447*
X02525Y02446*
X02532Y02447*
X02537Y02451*
X0254Y02456*
X02542Y02463*
X0254Y02469*
X02537Y02474*
X02532Y02478*
X02525Y02479*
G37*
G36*
X05578Y02534D02*
X05566Y02533D01*
X05555Y02528*
X05545Y02521*
X05538Y02511*
X05533Y025*
X05532Y02489*
X05533Y02477*
X05538Y02466*
X05545Y02456*
X05555Y02449*
X05566Y02444*
X05578Y02443*
X0559Y02444*
X05601Y02449*
X0561Y02456*
X05617Y02466*
X05622Y02477*
X05624Y02489*
X05622Y025*
X05617Y02511*
X0561Y02521*
X05601Y02528*
X0559Y02533*
X05578Y02534*
G37*
G36*
X02948Y02472D02*
X02942Y02471D01*
X02937Y02467*
X02933Y02462*
X02932Y02456*
X02933Y02449*
X02937Y02444*
X02942Y0244*
X02948Y02439*
X02955Y0244*
X0296Y02444*
X02963Y02449*
X02965Y02456*
X02963Y02462*
X0296Y02467*
X02955Y02471*
X02948Y02472*
G37*
G36*
X0299Y02457D02*
X02983Y02456D01*
X02976Y02452*
X02972Y02445*
X02971Y02438*
X02972Y02431*
X02976Y02424*
X02983Y0242*
X0299Y02419*
X02997Y0242*
X03004Y02424*
X03008Y02431*
X03009Y02438*
X03008Y02445*
X03004Y02452*
X02997Y02456*
X0299Y02457*
G37*
G36*
X02203D02*
X02195Y02456D01*
X02189Y02452*
X02185Y02445*
X02183Y02438*
X02185Y02431*
X02189Y02424*
X02195Y0242*
X02203Y02419*
X0221Y0242*
X02216Y02424*
X0222Y02431*
X02222Y02438*
X0222Y02445*
X02216Y02452*
X0221Y02456*
X02203Y02457*
G37*
G36*
X03617Y02553D02*
X03604Y02552D01*
X03592Y02548*
X0358Y02542*
X0357Y02533*
X03561Y02523*
X03555Y02512*
X03551Y02499*
X0355Y02486*
X03551Y02473*
X03555Y0246*
X03561Y02448*
X0357Y02438*
X0358Y0243*
X03592Y02424*
X03604Y0242*
X03617Y02418*
X03631Y0242*
X03643Y02424*
X03655Y0243*
X03665Y02438*
X03673Y02448*
X0368Y0246*
X03684Y02473*
X03685Y02486*
X03684Y02499*
X0368Y02512*
X03673Y02523*
X03665Y02533*
X03655Y02542*
X03643Y02548*
X03631Y02552*
X03617Y02553*
G37*
G36*
X01651D02*
X01638Y02552D01*
X01626Y02548*
X01614Y02542*
X01604Y02533*
X01595Y02523*
X01589Y02512*
X01585Y02499*
X01584Y02486*
X01585Y02473*
X01589Y0246*
X01595Y02448*
X01604Y02438*
X01614Y0243*
X01626Y02424*
X01638Y0242*
X01651Y02418*
X01665Y0242*
X01677Y02424*
X01689Y0243*
X01699Y02438*
X01707Y02448*
X01714Y0246*
X01718Y02473*
X01719Y02486*
X01718Y02499*
X01714Y02512*
X01707Y02523*
X01699Y02533*
X01689Y02542*
X01677Y02548*
X01665Y02552*
X01651Y02553*
G37*
G36*
X00199Y02545D02*
X00187Y02544D01*
X00175Y0254*
X00164Y02534*
X00154Y02526*
X00146Y02516*
X0014Y02505*
X00136Y02493*
X00135Y02481*
X00136Y02468*
X0014Y02456*
X00146Y02445*
X00154Y02435*
X00164Y02427*
X00175Y02421*
X00187Y02417*
X00199Y02416*
X00212Y02417*
X00224Y02421*
X00235Y02427*
X00245Y02435*
X00253Y02445*
X00259Y02456*
X00262Y02468*
X00264Y02481*
X00262Y02493*
X00259Y02505*
X00253Y02516*
X00245Y02526*
X00235Y02534*
X00224Y0254*
X00212Y02544*
X00199Y02545*
G37*
G36*
X02894Y02447D02*
X02888Y02446D01*
X02883Y02442*
X02879Y02437*
X02878Y02431*
X02879Y02424*
X02883Y02419*
X02888Y02415*
X02894Y02414*
X02901Y02415*
X02906Y02419*
X02907*
X02909Y02416*
X02914Y02412*
X0292Y02411*
X02927Y02412*
X02932Y02416*
X02935Y02421*
X02937Y02428*
X02935Y02434*
X02932Y02439*
X02927Y02443*
X0292Y02444*
X02914Y02443*
X02909Y02439*
X02908*
X02906Y02442*
X02901Y02446*
X02894Y02447*
G37*
G36*
X04039Y02422D02*
X04033Y02421D01*
X04028Y02417*
X04024Y02412*
X04023Y02406*
X04024Y02399*
X04028Y02394*
X04033Y0239*
X04039Y02389*
X04046Y0239*
X04051Y02394*
X04054Y02399*
X04056Y02406*
X04054Y02412*
X04051Y02417*
X04046Y02421*
X04039Y02422*
G37*
G36*
X03498Y02357D02*
X03492Y02356D01*
X03487Y02352*
X03483Y02347*
X03482Y02341*
X03483Y02334*
X03487Y02329*
X03492Y02325*
X03498Y02324*
X03505Y02325*
X0351Y02329*
X03513Y02334*
X03515Y02341*
X03513Y02347*
X0351Y02352*
X03505Y02356*
X03498Y02357*
G37*
G36*
X02726Y02309D02*
X0272Y02308D01*
X02715Y02304*
X02713Y02301*
X02709Y02304*
X02702Y02305*
X02696Y02304*
X02691Y023*
X02687Y02295*
X02686Y0229*
X02682Y02291*
X0268Y02297*
X02677Y02302*
X02672Y02306*
X02665Y02307*
X02659Y02306*
X02654Y02302*
X0265Y02297*
X02649Y02291*
X02648Y02289*
X02645Y0229*
X02639Y02289*
X02634Y02285*
X0263Y0228*
X02629Y02274*
X0263Y02267*
X02634Y02262*
X02639Y02258*
X02645Y02257*
X02652Y02258*
X02657Y02262*
X0266Y02267*
X02662Y02274*
X02663Y02275*
X02665Y02274*
X02672Y02275*
X02677Y02279*
X0268Y02284*
X02681Y02289*
X02686Y02289*
X02687Y02282*
X02691Y02277*
X02696Y02273*
X02702Y02272*
X02709Y02273*
X02714Y02277*
X02716Y0228*
X0272Y02277*
X02726Y02276*
X02733Y02277*
X02738Y02281*
X02741Y02286*
X02743Y02293*
X02741Y02299*
X02738Y02304*
X02733Y02308*
X02726Y02309*
G37*
G36*
X02475Y02307D02*
X02469Y02306D01*
X02464Y02302*
X02462Y02299*
X02457Y02297*
X02455Y02297*
X0245Y02298*
X02444Y02297*
X02439Y02293*
X02435Y02288*
X02434Y02282*
X02435Y02275*
X02439Y0227*
X02444Y02266*
X0245Y02265*
X02457Y02266*
X02462Y0227*
X02465Y02275*
X0247Y02275*
X02475Y02274*
X02482Y02275*
X02487Y02279*
X0249Y02284*
X02492Y02291*
X0249Y02297*
X02487Y02302*
X02482Y02306*
X02475Y02307*
G37*
G36*
X02803Y02323D02*
X02797Y02322D01*
X02792Y02318*
X02788Y02313*
X02787Y02307*
X02788Y023*
X02792Y02295*
X02797Y02291*
X02803Y0229*
X0281Y02291*
X02815Y02295*
X02818Y023*
X0282Y02307*
X02818Y02313*
X02815Y02318*
X0281Y02322*
X02803Y02323*
G37*
G36*
X02985Y02303D02*
X02979Y02302D01*
X02974Y02298*
X0297Y02293*
X02969Y02287*
X0297Y0228*
X02974Y02275*
X02979Y02271*
X02985Y0227*
X02992Y02271*
X02997Y02275*
X03Y0228*
X03002Y02287*
X03Y02293*
X02997Y02298*
X02992Y02302*
X02985Y02303*
G37*
G36*
X02942Y02302D02*
X02936Y02301D01*
X02931Y02297*
X02927Y02292*
X02926Y02286*
X02927Y02279*
X02931Y02274*
X02936Y0227*
X02942Y02269*
X02949Y0227*
X02954Y02274*
X02957Y02279*
X02959Y02286*
X02957Y02292*
X02954Y02297*
X02949Y02301*
X02942Y02302*
G37*
G36*
X05327Y02346D02*
X05317Y02345D01*
X05308Y02341*
X053Y02334*
X05294Y02326*
X0529Y02317*
X05288Y02307*
X0529Y02297*
X05294Y02288*
X053Y0228*
X05308Y02273*
X05317Y02269*
X05327Y02268*
X05337Y02269*
X05347Y02273*
X05355Y0228*
X05361Y02288*
X05365Y02297*
X05366Y02307*
X05365Y02317*
X05361Y02326*
X05355Y02334*
X05347Y02341*
X05337Y02345*
X05327Y02346*
G37*
G36*
X04927D02*
X04917Y02345D01*
X04908Y02341*
X049Y02334*
X04894Y02326*
X0489Y02317*
X04888Y02307*
X0489Y02297*
X04894Y02288*
X049Y0228*
X04908Y02273*
X04917Y02269*
X04927Y02268*
X04937Y02269*
X04947Y02273*
X04955Y0228*
X04961Y02288*
X04965Y02297*
X04966Y02307*
X04965Y02317*
X04961Y02326*
X04955Y02334*
X04947Y02341*
X04937Y02345*
X04927Y02346*
G37*
G36*
X04727D02*
X04717Y02345D01*
X04708Y02341*
X047Y02334*
X04694Y02326*
X0469Y02317*
X04688Y02307*
X0469Y02297*
X04694Y02288*
X047Y0228*
X04708Y02273*
X04717Y02269*
X04727Y02268*
X04737Y02269*
X04747Y02273*
X04755Y0228*
X04761Y02288*
X04765Y02297*
X04766Y02307*
X04765Y02317*
X04761Y02326*
X04755Y02334*
X04747Y02341*
X04737Y02345*
X04727Y02346*
G37*
G36*
X04327D02*
X04317Y02345D01*
X04308Y02341*
X043Y02334*
X04294Y02326*
X0429Y02317*
X04288Y02307*
X0429Y02297*
X04294Y02288*
X043Y0228*
X04308Y02273*
X04317Y02269*
X04327Y02268*
X04337Y02269*
X04347Y02273*
X04355Y0228*
X04361Y02288*
X04365Y02297*
X04366Y02307*
X04365Y02317*
X04361Y02326*
X04355Y02334*
X04347Y02341*
X04337Y02345*
X04327Y02346*
G37*
G36*
X02409Y0233D02*
X02403Y02329D01*
X02398Y02325*
X02394Y0232*
X02393Y02314*
X02394Y02307*
X02398Y02302*
X02399Y02301*
Y02295*
X02398Y02294*
X02394Y02289*
X02393Y02283*
X02394Y02276*
X02398Y02271*
X02403Y02267*
X02409Y02266*
X02416Y02267*
X02421Y02271*
X02424Y02276*
X02426Y02283*
X02424Y02289*
X02421Y02294*
X02419Y02295*
Y02301*
X02421Y02302*
X02424Y02307*
X02426Y02314*
X02424Y0232*
X02421Y02325*
X02416Y02329*
X02409Y0233*
G37*
G36*
X02579Y02297D02*
X02573Y02296D01*
X02568Y02292*
X02564Y02287*
X02563Y02281*
X02564Y02274*
X02568Y02269*
X02573Y02265*
X02579Y02264*
X02586Y02265*
X02591Y02269*
X02594Y02274*
X02596Y02281*
X02594Y02287*
X02591Y02292*
X02586Y02296*
X02579Y02297*
G37*
G36*
X03342Y02279D02*
X03336Y02278D01*
X03331Y02274*
X03327Y02269*
X03326Y02263*
X03327Y02256*
X03331Y02251*
X03336Y02247*
X03342Y02246*
X03349Y02247*
X03354Y02251*
X03357Y02256*
X03359Y02263*
X03357Y02269*
X03354Y02274*
X03349Y02278*
X03342Y02279*
G37*
G36*
X02841D02*
X02835Y02278D01*
X0283Y02274*
X02826Y02269*
X02825Y02263*
X02826Y02256*
X0283Y02251*
X02835Y02247*
X02841Y02246*
X02848Y02247*
X02853Y02251*
X02856Y02256*
X02858Y02263*
X02856Y02269*
X02853Y02274*
X02848Y02278*
X02841Y02279*
G37*
G36*
X00996Y02272D02*
X0099Y02271D01*
X00985Y02267*
X00981Y02262*
X0098Y02256*
X00981Y02249*
X00985Y02244*
X0099Y0224*
X00996Y02239*
X01003Y0224*
X01008Y02244*
X01011Y02249*
X01013Y02256*
X01011Y02262*
X01008Y02267*
X01003Y02271*
X00996Y02272*
G37*
G36*
X05634Y02252D02*
X05628Y02251D01*
X05623Y02247*
X05619Y02242*
X05618Y02236*
X05619Y02229*
X05623Y02224*
X05628Y0222*
X05634Y02219*
X05641Y0222*
X05646Y02224*
X05649Y02229*
X05651Y02236*
X05649Y02242*
X05646Y02247*
X05641Y02251*
X05634Y02252*
G37*
G36*
X02499D02*
X02493Y02251D01*
X02488Y02247*
X02484Y02242*
X02483Y02236*
X02484Y02229*
X02488Y02224*
X02493Y0222*
X02499Y02219*
X02506Y0222*
X02511Y02224*
X02514Y02229*
X02516Y02236*
X02514Y02242*
X02511Y02247*
X02506Y02251*
X02499Y02252*
G37*
G36*
X0233Y02231D02*
X02324Y0223D01*
X02319Y02226*
X02315Y02221*
X02314Y02215*
X02315Y02208*
X02319Y02203*
X02324Y02199*
X0233Y02198*
X02337Y02199*
X02342Y02203*
X02345Y02208*
X02347Y02215*
X02345Y02221*
X02342Y02226*
X02337Y0223*
X0233Y02231*
G37*
G36*
X05577Y0223D02*
X05571Y02229D01*
X05566Y02225*
X05562Y0222*
X05561Y02214*
X05562Y02207*
X05566Y02202*
X05571Y02198*
X05577Y02197*
X05584Y02198*
X05589Y02202*
X05592Y02207*
X05594Y02214*
X05592Y0222*
X05589Y02225*
X05584Y02229*
X05577Y0223*
G37*
G36*
X06424Y02197D02*
X06418Y02196D01*
X06413Y02192*
X06409Y02187*
X06408Y02181*
X06409Y02174*
X06413Y02169*
X06418Y02165*
X06424Y02164*
X06431Y02165*
X06436Y02169*
X06439Y02174*
X06441Y02181*
X06439Y02187*
X06436Y02192*
X06431Y02196*
X06424Y02197*
G37*
G36*
X01754Y02142D02*
X01748Y02141D01*
X01743Y02137*
X01739Y02132*
X01738Y02126*
X01739Y02119*
X01743Y02114*
X01748Y0211*
X01754Y02109*
X01761Y0211*
X01766Y02114*
X01769Y02119*
X01771Y02126*
X01769Y02132*
X01766Y02137*
X01761Y02141*
X01754Y02142*
G37*
G36*
X01619Y02137D02*
X01613Y02136D01*
X01608Y02132*
X01604Y02127*
X01603Y02121*
X01604Y02114*
X01608Y02109*
X01613Y02105*
X01619Y02104*
X01626Y02105*
X01631Y02109*
X01634Y02114*
X01636Y02121*
X01634Y02127*
X01631Y02132*
X01626Y02136*
X01619Y02137*
G37*
G36*
X01696Y02116D02*
X01689Y02114D01*
X01683Y0211*
X01679Y02104*
X01677Y02097*
X01679Y02089*
X01683Y02083*
X01689Y02079*
X01696Y02078*
X01704Y02079*
X0171Y02083*
X01714Y02089*
X01716Y02097*
X01714Y02104*
X0171Y0211*
X01704Y02114*
X01696Y02116*
G37*
G36*
X01884Y02087D02*
X01878Y02086D01*
X01873Y02082*
X01869Y02077*
X01868Y02071*
X01869Y02064*
X01873Y02059*
X01878Y02055*
X01884Y02054*
X01891Y02055*
X01896Y02059*
X01899Y02064*
X01901Y02071*
X01899Y02077*
X01896Y02082*
X01891Y02086*
X01884Y02087*
G37*
G36*
X01568Y02084D02*
X01561Y02082D01*
X01556Y02079*
X01553Y02073*
X01551Y02067*
X01553Y02061*
X01556Y02056*
X01561Y02052*
X01568Y02051*
X01574Y02052*
X01579Y02056*
X01583Y02061*
X01584Y02067*
X01583Y02073*
X01579Y02079*
X01574Y02082*
X01568Y02084*
G37*
G36*
X03571Y02116D02*
X03564Y02114D01*
X03558Y0211*
X03554Y02104*
X03552Y02097*
X03554Y02089*
X03558Y02083*
X03564Y02079*
X03568Y02078*
Y02073*
X03565Y02073*
X0356Y02069*
X03556Y02064*
X03555Y02058*
X03556Y02051*
X03558Y02049*
X03559Y02045*
X03558Y02041*
X03556Y02039*
X03555Y02033*
X03556Y02026*
X0356Y02021*
X03565Y02017*
X03571Y02016*
X03578Y02017*
X03583Y02021*
X03586Y02026*
X03588Y02033*
X03586Y02039*
X03585Y02041*
X03583Y02045*
X03585Y02049*
X03586Y02051*
X03588Y02058*
X03586Y02064*
X03583Y02069*
X03578Y02073*
X03575Y02073*
Y02078*
X03579Y02079*
X03585Y02083*
X03589Y02089*
X0359Y02097*
X03589Y02104*
X03585Y0211*
X03579Y02114*
X03571Y02116*
G37*
G36*
X02409Y01983D02*
X02403Y01982D01*
X02398Y01978*
X02394Y01973*
X02393Y01967*
X02394Y0196*
X02396Y01958*
X02392Y01955*
X02391Y01956*
X02384Y01957*
X02378Y01956*
X02373Y01952*
X02369Y01947*
X02368Y01941*
X02369Y01934*
X02373Y01929*
X02378Y01925*
X02384Y01924*
X02391Y01925*
X02396Y01929*
X02399Y01934*
X02401Y01941*
X02399Y01947*
X02398Y01949*
X02402Y01952*
X02403Y01951*
X02409Y0195*
X02416Y01951*
X02421Y01955*
X02424Y0196*
X02426Y01967*
X02424Y01973*
X02421Y01978*
X02416Y01982*
X02409Y01983*
G37*
G36*
X03298Y01987D02*
X03292Y01986D01*
X03287Y01982*
X03283Y01977*
X03282Y01971*
X03283Y01964*
X03287Y01959*
X03292Y01955*
X03298Y01954*
X03305Y01955*
X0331Y01959*
X03313Y01964*
X03315Y01971*
X03313Y01977*
X0331Y01982*
X03305Y01986*
X03298Y01987*
G37*
G36*
X01009Y01972D02*
X01003Y01971D01*
X00998Y01967*
X00994Y01962*
X00993Y01956*
X00994Y01949*
X00998Y01944*
X01003Y0194*
X01009Y01939*
X01016Y0194*
X01021Y01944*
X01024Y01949*
X01026Y01956*
X01024Y01962*
X01021Y01967*
X01016Y01971*
X01009Y01972*
G37*
G36*
X02299Y01932D02*
X02293Y01931D01*
X02288Y01927*
X02284Y01922*
X02283Y01916*
X02284Y01909*
X02288Y01904*
X02293Y019*
X02299Y01899*
X02306Y019*
X02311Y01904*
X02314Y01909*
X02316Y01916*
X02314Y01922*
X02311Y01927*
X02306Y01931*
X02299Y01932*
G37*
G36*
X00199Y0202D02*
X00187Y02019D01*
X00175Y02015*
X00164Y02009*
X00154Y02001*
X00146Y01991*
X0014Y0198*
X00136Y01968*
X00135Y01956*
X00136Y01943*
X0014Y01931*
X00146Y0192*
X00154Y0191*
X00164Y01902*
X00175Y01896*
X00187Y01892*
X00199Y01891*
X00212Y01892*
X00224Y01896*
X00235Y01902*
X00245Y0191*
X00253Y0192*
X00259Y01931*
X00262Y01943*
X00264Y01956*
X00262Y01968*
X00259Y0198*
X00253Y01991*
X00245Y02001*
X00235Y02009*
X00224Y02015*
X00212Y02019*
X00199Y0202*
G37*
G36*
X03554Y01907D02*
X03548Y01906D01*
X03543Y01902*
X03539Y01897*
X03538Y01891*
X03539Y01884*
X03543Y01879*
X03548Y01875*
X03554Y01874*
X03561Y01875*
X03566Y01879*
X03569Y01884*
X03571Y01891*
X03569Y01897*
X03566Y01902*
X03561Y01906*
X03554Y01907*
G37*
G36*
X03392Y01887D02*
X03386Y01886D01*
X03381Y01882*
X03377Y01877*
X03376Y01871*
X03377Y01864*
X03381Y01859*
X03386Y01855*
X03392Y01854*
X03399Y01855*
X03404Y01859*
X03407Y01864*
X03409Y01871*
X03407Y01877*
X03404Y01882*
X03399Y01886*
X03392Y01887*
G37*
G36*
X03439Y01887D02*
X03433Y01886D01*
X03427Y01882*
X03424Y01877*
X03422Y0187*
X03424Y01864*
X03427Y01859*
X03433Y01855*
X03439Y01854*
X03445Y01855*
X0345Y01859*
X03454Y01864*
X03455Y0187*
X03454Y01877*
X0345Y01882*
X03445Y01886*
X03439Y01887*
G37*
G36*
X03804Y01856D02*
X03798Y01855D01*
X03793Y01851*
X03789Y01846*
X03788Y0184*
X03789Y01833*
X03793Y01828*
X03798Y01824*
X03804Y01823*
X03811Y01824*
X03816Y01828*
X03819Y01833*
X03821Y0184*
X03819Y01846*
X03816Y01851*
X03811Y01855*
X03804Y01856*
G37*
G36*
X03329Y01842D02*
X03322Y01841D01*
X03317Y01837*
X03314Y01832*
X03312Y01826*
X03314Y01819*
X03317Y01814*
X03322Y0181*
X03329Y01809*
X03335Y0181*
X0334Y01814*
X03344Y01819*
X03345Y01826*
X03344Y01832*
X0334Y01837*
X03335Y01841*
X03329Y01842*
G37*
G36*
X01393Y01833D02*
X01387Y01832D01*
X01382Y01828*
X01378Y01823*
X01377Y01816*
X01378Y0181*
X01382Y01805*
X01387Y01801*
X01393Y018*
X01399Y01801*
X01405Y01805*
X01408Y0181*
X0141Y01816*
X01408Y01823*
X01405Y01828*
X01399Y01832*
X01393Y01833*
G37*
G36*
X03944Y01832D02*
X03938Y01831D01*
X03933Y01827*
X03929Y01822*
X03928Y01816*
X03929Y01809*
X03933Y01804*
X03938Y018*
X03944Y01799*
X03951Y018*
X03956Y01804*
X03959Y01809*
X03961Y01816*
X03959Y01822*
X03956Y01827*
X03951Y01831*
X03944Y01832*
G37*
G36*
X03056Y01828D02*
X0305Y01826D01*
X03045Y01823*
X03041Y01818*
X0304Y01811*
X03041Y01805*
X03045Y018*
X0305Y01796*
X03056Y01795*
X03063Y01796*
X03068Y018*
X03071Y01805*
X03073Y01811*
X03071Y01818*
X03068Y01823*
X03063Y01826*
X03056Y01828*
G37*
G36*
X01879D02*
X01873Y01826D01*
X01868Y01823*
X01864Y01818*
X01863Y01811*
X01864Y01805*
X01868Y018*
X01873Y01796*
X01879Y01795*
X01886Y01796*
X01891Y018*
X01895Y01805*
X01896Y01811*
X01895Y01818*
X01891Y01823*
X01886Y01826*
X01879Y01828*
G37*
G36*
X04064Y01812D02*
X04058Y01811D01*
X04053Y01807*
X04049Y01802*
X04048Y01796*
X04049Y01789*
X04053Y01784*
X04058Y0178*
X04064Y01779*
X04071Y0178*
X04076Y01784*
X04079Y01789*
X04081Y01796*
X04079Y01802*
X04076Y01807*
X04071Y01811*
X04064Y01812*
G37*
G36*
X02579Y01806D02*
X02573Y01805D01*
X02568Y01801*
X02564Y01796*
X02563Y0179*
X02564Y01783*
X02568Y01778*
X02573Y01774*
X02579Y01773*
X02586Y01774*
X02591Y01778*
X02594Y01783*
X02596Y0179*
X02594Y01796*
X02591Y01801*
X02586Y01805*
X02579Y01806*
G37*
G36*
X02626Y01786D02*
X0262Y01785D01*
X02615Y01781*
X02611Y01776*
X0261Y0177*
X02611Y01763*
X02615Y01758*
X0262Y01754*
X02626Y01753*
X02633Y01754*
X02638Y01758*
X02641Y01763*
X02643Y0177*
X02641Y01776*
X02638Y01781*
X02633Y01785*
X02626Y01786*
G37*
G36*
X03719Y01782D02*
X03713Y01781D01*
X03708Y01777*
X03704Y01772*
X03703Y01766*
X03704Y01759*
X03708Y01754*
X03713Y0175*
X03719Y01749*
X03726Y0175*
X03731Y01754*
X03734Y01759*
X03736Y01766*
X03734Y01772*
X03731Y01777*
X03726Y01781*
X03719Y01782*
G37*
G36*
X02549Y01771D02*
X02543Y0177D01*
X02538Y01766*
X02534Y01761*
X02533Y01755*
X02534Y01748*
X02538Y01743*
X02543Y01739*
X02549Y01738*
X02556Y01739*
X02561Y01743*
X02564Y01748*
X02566Y01755*
X02564Y01761*
X02561Y01766*
X02556Y0177*
X02549Y01771*
G37*
G36*
X04134Y01767D02*
X04128Y01766D01*
X04123Y01762*
X04119Y01757*
X04118Y01751*
X04119Y01744*
X04123Y01739*
X04128Y01735*
X04134Y01734*
X04141Y01735*
X04146Y01739*
X04149Y01744*
X04151Y01751*
X04149Y01757*
X04146Y01762*
X04141Y01766*
X04134Y01767*
G37*
G36*
X02604Y0175D02*
X02598Y01749D01*
X02593Y01745*
X02589Y0174*
X02588Y01734*
X02589Y01727*
X02593Y01722*
X02598Y01718*
X02604Y01717*
X02611Y01718*
X02616Y01722*
X02619Y01727*
X02621Y01734*
X02619Y0174*
X02616Y01745*
X02611Y01749*
X02604Y0175*
G37*
G36*
X00988Y01733D02*
X00981Y01732D01*
X00976Y01729*
X00973Y01723*
X00971Y01717*
X00973Y01711*
X00976Y01705*
X00981Y01702*
X00988Y01701*
X00994Y01702*
X00999Y01705*
X01003Y01711*
X01004Y01717*
X01003Y01723*
X00999Y01729*
X00994Y01732*
X00988Y01733*
G37*
G36*
X03197Y0173D02*
X03191Y01729D01*
X03185Y01725*
X03182Y0172*
X0318Y01714*
X03182Y01707*
X03185Y01702*
X03191Y01698*
X03197Y01697*
X03203Y01698*
X03208Y01702*
X03212Y01707*
X03213Y01714*
X03212Y0172*
X03208Y01725*
X03203Y01729*
X03197Y0173*
G37*
G36*
X03589Y01727D02*
X03583Y01726D01*
X03578Y01722*
X03574Y01717*
X03573Y01711*
X03574Y01704*
X03578Y01699*
X03583Y01695*
X03589Y01694*
X03596Y01695*
X03601Y01699*
X03604Y01704*
X03606Y01711*
X03604Y01717*
X03601Y01722*
X03596Y01726*
X03589Y01727*
G37*
G36*
X01893Y01709D02*
X01887Y01708D01*
X01882Y01704*
X01878Y01699*
X01877Y01693*
X01878Y01686*
X01882Y01681*
X01887Y01677*
X01893Y01676*
X019Y01677*
X01905Y01681*
X01908Y01686*
X0191Y01693*
X01908Y01699*
X01905Y01704*
X019Y01708*
X01893Y01709*
G37*
G36*
X03803Y01707D02*
X03797Y01706D01*
X03792Y01702*
X03788Y01697*
X03787Y01691*
X03788Y01684*
X03792Y01679*
X03797Y01675*
X03803Y01674*
X0381Y01675*
X03815Y01679*
X03818Y01684*
X0382Y01691*
X03818Y01697*
X03815Y01702*
X0381Y01706*
X03803Y01707*
G37*
G36*
X03724Y01691D02*
X03718Y0169D01*
X03713Y01686*
X03709Y01681*
X03708Y01675*
X03709Y01668*
X03713Y01663*
X03718Y01659*
X03724Y01658*
X03731Y01659*
X03736Y01663*
X03739Y01668*
X03741Y01675*
X03739Y01681*
X03736Y01686*
X03731Y0169*
X03724Y01691*
G37*
G36*
X01822Y0169D02*
X01816Y01689D01*
X01811Y01685*
X01807Y0168*
X01806Y01674*
X01807Y01667*
X01811Y01662*
X01816Y01658*
X01822Y01657*
X01829Y01658*
X01834Y01662*
X01837Y01667*
X01839Y01674*
X01837Y0168*
X01834Y01685*
X01829Y01689*
X01822Y0169*
G37*
G36*
X03773Y01682D02*
X03767Y01681D01*
X03762Y01677*
X03758Y01672*
X03757Y01666*
X03758Y01659*
X03762Y01654*
X03767Y01651*
X03773Y01649*
X0378Y01651*
X03785Y01654*
X03788Y01659*
X0379Y01666*
X03788Y01672*
X03785Y01677*
X0378Y01681*
X03773Y01682*
G37*
G36*
X06844Y01677D02*
X06838Y01676D01*
X06833Y01672*
X06829Y01667*
X06828Y01661*
X06829Y01654*
X06833Y01649*
X06838Y01645*
X06844Y01644*
X06851Y01645*
X06856Y01649*
X06859Y01654*
X06861Y01661*
X06859Y01667*
X06856Y01672*
X06851Y01676*
X06844Y01677*
G37*
G36*
X03224Y01677D02*
X03218Y01676D01*
X03213Y01672*
X03209Y01667*
X03208Y01661*
X03209Y01655*
X03213Y01649*
X03218Y01646*
X03224Y01645*
X03231Y01646*
X03235Y01649*
X03239Y01649*
X03241Y01649*
X03246Y01645*
X03252Y01644*
X03259Y01645*
X03264Y01649*
X03267Y01654*
X03269Y01661*
X03267Y01667*
X03264Y01672*
X03259Y01676*
X03252Y01677*
X03246Y01676*
X03242Y01673*
X03238Y01672*
X03235Y01673*
X03231Y01676*
X03224Y01677*
G37*
G36*
X02666Y01656D02*
X0266Y01655D01*
X02655Y01651*
X02651Y01646*
X0265Y0164*
X02651Y01635*
X02647Y01631*
X02647Y01631*
X02643Y01632*
X02637Y01631*
X02632Y01627*
X02628Y01622*
X02627Y01616*
X02628Y01609*
X02632Y01604*
X02637Y016*
X02643Y01599*
X0265Y016*
X02655Y01604*
X02658Y01609*
X0266Y01616*
X02659Y0162*
X02662Y01624*
X02663Y01624*
X02666Y01623*
X02673Y01624*
X02678Y01628*
X02681Y01633*
X02683Y0164*
X02681Y01646*
X02678Y01651*
X02673Y01655*
X02666Y01656*
G37*
G36*
X04134Y01667D02*
X04128Y01666D01*
X04123Y01662*
X04119Y01657*
X04118Y01651*
X04119Y01644*
X04123Y01639*
X04128Y01635*
X04133Y01634*
X04135Y01631*
X04136Y01629*
X04136Y01629*
X04134Y01623*
X04136Y01617*
X04139Y01612*
X04145Y01608*
X04151Y01607*
X04157Y01608*
X04161Y01611*
X04164Y01607*
X04164Y01607*
X04163Y01601*
X04164Y01594*
X04168Y01589*
X04173Y01585*
X04179Y01584*
X04186Y01585*
X04191Y01589*
X04194Y01594*
X04196Y01601*
X04194Y01607*
X04191Y01612*
X04186Y01616*
X04179Y01617*
X04173Y01616*
X04169Y01613*
X04166Y01617*
X04166Y01617*
X04167Y01623*
X04166Y01629*
X04162Y01635*
X04157Y01638*
X04152Y01639*
X0415Y01643*
X04149Y01644*
X04149Y01644*
X04151Y01651*
X04149Y01657*
X04146Y01662*
X04141Y01666*
X04134Y01667*
G37*
G36*
X02719Y01607D02*
X02713Y01606D01*
X02708Y01602*
X02704Y01597*
X02703Y01591*
X02704Y01584*
X02708Y01579*
X02713Y01575*
X02719Y01574*
X02726Y01575*
X02731Y01579*
X02734Y01584*
X02736Y01591*
X02734Y01597*
X02731Y01602*
X02726Y01606*
X02719Y01607*
G37*
G36*
X03894Y01582D02*
X03888Y01581D01*
X03883Y01577*
X03879Y01572*
X03878Y01566*
X03879Y01559*
X03883Y01554*
X03888Y0155*
X03894Y01549*
X03901Y0155*
X03906Y01554*
X03909Y01559*
X03911Y01566*
X03909Y01572*
X03906Y01577*
X03901Y01581*
X03894Y01582*
G37*
G36*
X03969Y01568D02*
X03963Y01567D01*
X03958Y01563*
X03954Y01558*
X03953Y01552*
X03954Y01545*
X03958Y0154*
X03963Y01536*
X03969Y01535*
X03976Y01536*
X03978Y01538*
X03983Y01539*
X03985Y01537*
X03988Y01535*
X03994Y01534*
X04001Y01535*
X04006Y01539*
X04009Y01544*
X04011Y01551*
X04009Y01557*
X04006Y01562*
X04001Y01566*
X03994Y01567*
X03988Y01566*
X03983Y01562*
X03982*
X03981Y01563*
X03976Y01567*
X03969Y01568*
G37*
G36*
X04034Y01562D02*
X04028Y01561D01*
X04023Y01557*
X04019Y01552*
X04018Y01546*
X04019Y01539*
X04023Y01534*
X04028Y0153*
X04034Y01529*
X04041Y0153*
X04046Y01534*
X04049Y01539*
X04051Y01546*
X04049Y01552*
X04046Y01557*
X04041Y01561*
X04034Y01562*
G37*
G36*
X03924Y01552D02*
X03918Y01551D01*
X03913Y01547*
X03909Y01542*
X03908Y01536*
X03909Y01529*
X03913Y01524*
X03918Y0152*
X03924Y01519*
X03931Y0152*
X03936Y01524*
X03939Y01529*
X03941Y01536*
X03939Y01542*
X03936Y01547*
X03931Y01551*
X03924Y01552*
G37*
G36*
X02894Y01577D02*
X02888Y01576D01*
X02883Y01572*
X02879Y01567*
X02878Y01561*
X02879Y01554*
X02883Y01549*
X02888Y01545*
X02894Y01544*
X02901Y01545*
X02901Y01546*
X02904Y01542*
X02904Y01542*
X02903Y01536*
X02904Y01529*
X02908Y01524*
X02913Y0152*
X02919Y01519*
X02926Y0152*
X02931Y01524*
X02934Y01529*
X02936Y01536*
X02934Y01542*
X02931Y01547*
X02926Y01551*
X02919Y01552*
X02913Y01551*
X02913Y0155*
X02909Y01554*
X02909Y01554*
X02911Y01561*
X02909Y01567*
X02906Y01572*
X02901Y01576*
X02894Y01577*
G37*
G36*
X01719Y01552D02*
X01713Y01551D01*
X01708Y01547*
X01704Y01542*
X01703Y01536*
X01704Y01529*
X01708Y01524*
X01713Y0152*
X01719Y01519*
X01726Y0152*
X01731Y01524*
X01734Y01529*
X01736Y01536*
X01734Y01542*
X01731Y01547*
X01726Y01551*
X01719Y01552*
G37*
G36*
X01897Y01532D02*
X01891Y01531D01*
X01885Y01528*
X01882Y01522*
X0188Y01516*
X01882Y0151*
X01885Y01504*
X01891Y01501*
X01897Y015*
X01903Y01501*
X01908Y01504*
X01912Y0151*
X01913Y01516*
X01912Y01522*
X01908Y01528*
X01903Y01531*
X01897Y01532*
G37*
G36*
X04064Y01527D02*
X04058Y01526D01*
X04053Y01522*
X04049Y01517*
X04048Y01511*
X04049Y01504*
X04053Y01499*
X04058Y01495*
X04064Y01494*
X04071Y01495*
X04076Y01499*
X04079Y01504*
X04081Y01511*
X04079Y01517*
X04076Y01522*
X04071Y01526*
X04064Y01527*
G37*
G36*
X03864D02*
X03858Y01526D01*
X03853Y01522*
X03849Y01517*
X03848Y01511*
X03849Y01504*
X03853Y01499*
X03858Y01495*
X03864Y01494*
X03871Y01495*
X03876Y01499*
X03879Y01504*
X03881Y01511*
X03879Y01517*
X03876Y01522*
X03871Y01526*
X03864Y01527*
G37*
G36*
X02274Y01522D02*
X02268Y01521D01*
X02263Y01517*
X02259Y01512*
X02258Y01506*
X02259Y01499*
X02263Y01494*
X02268Y0149*
X02274Y01489*
X02281Y0149*
X02286Y01494*
X02289Y01499*
X02291Y01506*
X02289Y01512*
X02286Y01517*
X02281Y01521*
X02274Y01522*
G37*
G36*
X03834Y01497D02*
X03828Y01496D01*
X03823Y01492*
X03819Y01487*
X03818Y01481*
X03819Y01474*
X03823Y01469*
X03828Y01465*
X03834Y01464*
X03841Y01465*
X03846Y01469*
X03849Y01474*
X03851Y01481*
X03849Y01487*
X03846Y01492*
X03841Y01496*
X03834Y01497*
G37*
G36*
X02694D02*
X02688Y01496D01*
X02683Y01492*
X02679Y01487*
X02678Y01481*
X02679Y01474*
X02683Y01469*
X02688Y01465*
X02694Y01464*
X02701Y01465*
X02706Y01469*
X02709Y01474*
X02711Y01481*
X02709Y01487*
X02706Y01492*
X02701Y01496*
X02694Y01497*
G37*
G36*
X03549Y01457D02*
X03543Y01456D01*
X03538Y01452*
X03534Y01447*
X03533Y01441*
X03534Y01434*
X03538Y01429*
X03543Y01425*
X03549Y01424*
X03556Y01425*
X03561Y01429*
X03564Y01434*
X03566Y01441*
X03564Y01447*
X03561Y01452*
X03556Y01456*
X03549Y01457*
G37*
G36*
X02446Y01453D02*
X0244Y01452D01*
X02435Y01448*
X02431Y01443*
X0243Y01437*
X02431Y0143*
X02435Y01425*
X0244Y01421*
X02446Y0142*
X02453Y01421*
X02458Y01425*
X02461Y0143*
X02463Y01437*
X02461Y01443*
X02458Y01448*
X02453Y01452*
X02446Y01453*
G37*
G36*
X01008Y01446D02*
X01002Y01445D01*
X00997Y01441*
X00993Y01436*
X00992Y0143*
X00993Y01423*
X00997Y01418*
X01002Y01414*
X01008Y01413*
X01015Y01414*
X0102Y01418*
X01023Y01423*
X01025Y0143*
X01023Y01436*
X0102Y01441*
X01015Y01445*
X01008Y01446*
G37*
G36*
X02083Y01427D02*
X02077Y01426D01*
X02072Y01423*
X02068Y01417*
X02067Y01411*
X02068Y01405*
X02068Y01405*
X02066Y01402*
X02065Y01401*
X02059Y01402*
X02053Y01401*
X02048Y01397*
X02044Y01392*
X02043Y01386*
X02044Y01379*
X02048Y01374*
X02053Y0137*
X02059Y01369*
X02066Y0137*
X02071Y01374*
X02074Y01379*
X02076Y01386*
X02074Y01392*
X02074Y01392*
X02076Y01395*
X02078Y01396*
X02083Y01395*
X0209Y01396*
X02095Y014*
X02098Y01405*
X021Y01411*
X02098Y01417*
X02095Y01423*
X0209Y01426*
X02083Y01427*
G37*
G36*
X03407Y01427D02*
X03401Y01426D01*
X03395Y01422*
X03392Y01417*
X0339Y01411*
X03392Y01405*
X03395Y014*
X03391Y01397*
X03386Y01401*
X03379Y01402*
X03373Y01401*
X03368Y01397*
X03364Y01392*
X03363Y01386*
X03364Y01379*
X03368Y01374*
X03373Y0137*
X03379Y01369*
X03385Y0137*
X03388Y01368*
X03389Y01367*
X03388Y01363*
X03389Y01357*
X03392Y01353*
X03392Y01352*
X03389Y01349*
X03388Y01349*
X03386Y01351*
X03379Y01352*
X03373Y01351*
X03368Y01347*
X03364Y01342*
X03363Y01336*
X03364Y01329*
X03368Y01324*
X03373Y0132*
X03379Y01319*
X03386Y0132*
X03391Y01324*
X03394Y01329*
X03396Y01336*
X03394Y01342*
X03392Y01345*
X03392Y01346*
X03395Y0135*
X03396Y01349*
X03398Y01348*
X03404Y01347*
X03411Y01348*
X03416Y01351*
X03419Y01357*
X03421Y01363*
X03419Y01369*
X03416Y01374*
X03411Y01378*
X03404Y01379*
X03399Y01378*
X03396Y0138*
X03395Y01382*
X03396Y01386*
X03394Y01392*
X03391Y01396*
X03395Y01399*
X03401Y01396*
X03407Y01395*
X03413Y01396*
X03418Y01399*
X03422Y01405*
X03423Y01411*
X03422Y01417*
X03418Y01422*
X03413Y01426*
X03407Y01427*
G37*
G36*
X00199Y01495D02*
X00187Y01494D01*
X00175Y0149*
X00164Y01484*
X00154Y01476*
X00146Y01466*
X0014Y01455*
X00136Y01443*
X00135Y01431*
X00136Y01418*
X0014Y01406*
X00146Y01395*
X00154Y01385*
X00164Y01377*
X00175Y01371*
X00187Y01367*
X00199Y01366*
X00212Y01367*
X00224Y01371*
X00235Y01377*
X00245Y01385*
X00253Y01395*
X00259Y01406*
X00262Y01418*
X00264Y01431*
X00262Y01443*
X00259Y01455*
X00253Y01466*
X00245Y01476*
X00235Y01484*
X00224Y0149*
X00212Y01494*
X00199Y01495*
G37*
G36*
X02028Y01377D02*
X02022Y01376D01*
X02017Y01373*
X02013Y01367*
X02012Y01361*
X02013Y01355*
X02013Y01355*
X02011Y01352*
X0201Y01351*
X02004Y01352*
X01998Y01351*
X01993Y01347*
X01989Y01342*
X01988Y01336*
X01989Y01329*
X01993Y01324*
X01998Y0132*
X02004Y01319*
X02011Y0132*
X02016Y01324*
X02019Y01329*
X02021Y01336*
X02019Y01342*
X02019Y01342*
X02021Y01345*
X02023Y01346*
X02028Y01345*
X02035Y01346*
X0204Y0135*
X02043Y01355*
X02045Y01361*
X02043Y01367*
X0204Y01373*
X02035Y01376*
X02028Y01377*
G37*
G36*
X02502Y01332D02*
X02496Y01331D01*
X02491Y01327*
X02487Y01322*
X02486Y01316*
X02487Y01309*
X02491Y01304*
X02496Y013*
X02502Y01299*
X02509Y013*
X02514Y01304*
X02517Y01309*
X02519Y01316*
X02517Y01322*
X02514Y01327*
X02509Y01331*
X02502Y01332*
G37*
G36*
X01696Y01329D02*
X01689Y01327D01*
X01683Y01323*
X01679Y01317*
X01677Y01309*
X01679Y01302*
X01683Y01296*
X01689Y01292*
X01696Y0129*
X01704Y01292*
X0171Y01296*
X01714Y01302*
X01716Y01309*
X01714Y01317*
X0171Y01323*
X01704Y01327*
X01696Y01329*
G37*
G36*
X03571Y01328D02*
X03564Y01327D01*
X03558Y01323*
X03554Y01317*
X03552Y01309*
X03554Y01302*
X03558Y01296*
X03564Y01292*
X03571Y0129*
X03579Y01292*
X03585Y01296*
X03589Y01302*
X0359Y01309*
X03589Y01317*
X03585Y01323*
X03579Y01327*
X03571Y01328*
G37*
G36*
X01798Y0132D02*
X01791Y01319D01*
X01786Y01315*
X01783Y0131*
X01781Y01304*
X01783Y01297*
X01786Y01292*
X01791Y01289*
X01798Y01287*
X01804Y01289*
X01809Y01292*
X01813Y01297*
X01814Y01304*
X01813Y0131*
X01809Y01315*
X01804Y01319*
X01798Y0132*
G37*
G36*
X02206Y01314D02*
X022Y01313D01*
X02195Y01309*
X02191Y01304*
X0219Y01298*
X02191Y01291*
X02195Y01286*
X022Y01282*
X02206Y01281*
X02213Y01282*
X02218Y01286*
X02221Y01291*
X02223Y01298*
X02221Y01304*
X02218Y01309*
X02213Y01313*
X02206Y01314*
G37*
G36*
X01567Y01301D02*
X01561Y013D01*
X01556Y01296*
X01552Y01291*
X01551Y01285*
X01552Y01279*
X01556Y01273*
X01561Y0127*
X01567Y01269*
X01574Y0127*
X01579Y01273*
X01582Y01279*
X01584Y01285*
X01582Y01291*
X01579Y01296*
X01574Y013*
X01567Y01301*
G37*
G36*
X00996Y01203D02*
X00989Y01202D01*
X00984Y01198*
X0098Y01193*
X00979Y01187*
X0098Y0118*
X00984Y01175*
X00989Y01171*
X00996Y0117*
X01002Y01171*
X01007Y01175*
X01011Y0118*
X01012Y01187*
X01011Y01193*
X01007Y01198*
X01002Y01202*
X00996Y01203*
G37*
G36*
X02826Y00992D02*
X0282Y00991D01*
X02815Y00987*
X0281*
X02805Y00991*
X02799Y00992*
X02792Y00991*
X02787Y00987*
X02786Y00986*
X0278*
X02779Y00987*
X02773Y00991*
X02767Y00992*
X02761Y00991*
X02756Y00987*
X02751*
X02746Y00991*
X0274Y00992*
X02733Y00991*
X02728Y00987*
X02727Y00986*
X02721*
X0272Y00987*
X02714Y00991*
X02708Y00992*
X02702Y00991*
X02697Y00987*
X02692*
X02687Y00991*
X02681Y00992*
X02674Y00991*
X02669Y00987*
X02668Y00986*
X02662*
X02661Y00987*
X02655Y00991*
X02649Y00992*
X02643Y00991*
X02638Y00987*
X02633*
X02628Y00991*
X02622Y00992*
X02615Y00991*
X0261Y00987*
X02606Y00982*
X02605Y00976*
X02606Y0097*
X0261Y00964*
X02615Y00961*
X02622Y0096*
X02628Y00961*
X02633Y00964*
X02638*
X02643Y00961*
X02649Y0096*
X02655Y00961*
X02661Y00964*
X02662Y00966*
X02668*
X02669Y00964*
X02674Y00961*
X02681Y0096*
X02687Y00961*
X02692Y00964*
X02697*
X02702Y00961*
X02708Y0096*
X02714Y00961*
X0272Y00964*
X02721Y00966*
X02727*
X02728Y00964*
X02733Y00961*
X0274Y0096*
X02746Y00961*
X02751Y00964*
X02756*
X02761Y00961*
X02767Y0096*
X02773Y00961*
X02779Y00964*
X0278Y00966*
X02786*
X02787Y00964*
X02792Y00961*
X02799Y0096*
X02805Y00961*
X0281Y00964*
X02815*
X0282Y00961*
X02826Y0096*
X02833Y00961*
X02838Y00964*
X02841Y0097*
X02843Y00976*
X02841Y00982*
X02838Y00987*
X02833Y00991*
X02826Y00992*
G37*
G36*
X04366Y01045D02*
X04289D01*
Y00968*
X04366*
Y01045*
G37*
G36*
X05327Y01046D02*
X05317Y01045D01*
X05308Y01041*
X053Y01034*
X05294Y01026*
X0529Y01017*
X05288Y01007*
X0529Y00997*
X05294Y00988*
X053Y0098*
X05308Y00973*
X05317Y00969*
X05327Y00968*
X05337Y00969*
X05347Y00973*
X05355Y0098*
X05361Y00988*
X05365Y00997*
X05366Y01007*
X05365Y01017*
X05361Y01026*
X05355Y01034*
X05347Y01041*
X05337Y01045*
X05327Y01046*
G37*
G36*
X05127D02*
X05117Y01045D01*
X05108Y01041*
X051Y01034*
X05094Y01026*
X0509Y01017*
X05088Y01007*
X0509Y00997*
X05094Y00988*
X051Y0098*
X05108Y00973*
X05117Y00969*
X05127Y00968*
X05137Y00969*
X05147Y00973*
X05155Y0098*
X05161Y00988*
X05165Y00997*
X05166Y01007*
X05165Y01017*
X05161Y01026*
X05155Y01034*
X05147Y01041*
X05137Y01045*
X05127Y01046*
G37*
G36*
X04927D02*
X04917Y01045D01*
X04908Y01041*
X049Y01034*
X04894Y01026*
X0489Y01017*
X04888Y01007*
X0489Y00997*
X04894Y00988*
X049Y0098*
X04908Y00973*
X04917Y00969*
X04927Y00968*
X04937Y00969*
X04947Y00973*
X04955Y0098*
X04961Y00988*
X04965Y00997*
X04966Y01007*
X04965Y01017*
X04961Y01026*
X04955Y01034*
X04947Y01041*
X04937Y01045*
X04927Y01046*
G37*
G36*
X0299Y00977D02*
X02983Y00976D01*
X02976Y00972*
X02972Y00965*
X02971Y00958*
X02972Y00951*
X02976Y00945*
X02983Y0094*
X0299Y00939*
X02997Y0094*
X03004Y00945*
X03008Y00951*
X03009Y00958*
X03008Y00965*
X03004Y00972*
X02997Y00976*
X0299Y00977*
G37*
G36*
X02203D02*
X02195Y00976D01*
X02189Y00972*
X02185Y00965*
X02183Y00958*
X02185Y00951*
X02189Y00945*
X02195Y0094*
X02203Y00939*
X0221Y0094*
X02216Y00945*
X0222Y00951*
X02222Y00958*
X0222Y00965*
X02216Y00972*
X0221Y00976*
X02203Y00977*
G37*
G36*
X02478Y00953D02*
X02472Y00952D01*
X02467Y00948*
X02463Y00943*
X02462Y00937*
X02463Y0093*
X02467Y00925*
X02472Y00921*
X02478Y0092*
X02485Y00921*
X0249Y00925*
X02493Y0093*
X02495Y00937*
X02493Y00943*
X0249Y00948*
X02485Y00952*
X02478Y00953*
G37*
G36*
X01004Y00922D02*
X00998Y00921D01*
X00993Y00917*
X00989Y00912*
X00988Y00906*
X00989Y00899*
X00993Y00894*
X00998Y0089*
X01004Y00889*
X01011Y0089*
X01016Y00894*
X01019Y00899*
X01021Y00906*
X01019Y00912*
X01016Y00917*
X01011Y00921*
X01004Y00922*
G37*
G36*
X03617Y00983D02*
X03604Y00982D01*
X03592Y00978*
X0358Y00972*
X0357Y00963*
X03561Y00953*
X03555Y00942*
X03551Y00929*
X0355Y00916*
X03551Y00903*
X03555Y0089*
X03561Y00878*
X0357Y00868*
X0358Y0086*
X03592Y00854*
X03604Y0085*
X03617Y00848*
X03631Y0085*
X03643Y00854*
X03655Y0086*
X03665Y00868*
X03673Y00878*
X0368Y0089*
X03684Y00903*
X03685Y00916*
X03684Y00929*
X0368Y00942*
X03673Y00953*
X03665Y00963*
X03655Y00972*
X03643Y00978*
X03631Y00982*
X03617Y00983*
G37*
G36*
X01652D02*
X01639Y00982D01*
X01627Y00978*
X01615Y00972*
X01605Y00963*
X01596Y00953*
X0159Y00942*
X01586Y00929*
X01585Y00916*
X01586Y00903*
X0159Y0089*
X01596Y00878*
X01605Y00868*
X01615Y0086*
X01627Y00854*
X01639Y0085*
X01652Y00848*
X01666Y0085*
X01678Y00854*
X0169Y0086*
X017Y00868*
X01708Y00878*
X01715Y0089*
X01719Y00903*
X0172Y00916*
X01719Y00929*
X01715Y00942*
X01708Y00953*
X017Y00963*
X0169Y00972*
X01678Y00978*
X01666Y00982*
X01652Y00983*
G37*
G36*
X05578Y00936D02*
X05566Y00934D01*
X05555Y0093*
X05545Y00923*
X05538Y00913*
X05533Y00902*
X05532Y0089*
X05533Y00878*
X05538Y00867*
X05545Y00858*
X05555Y0085*
X05566Y00846*
X05578Y00844*
X0559Y00846*
X05601Y0085*
X0561Y00858*
X05617Y00867*
X05622Y00878*
X05624Y0089*
X05622Y00902*
X05617Y00913*
X0561Y00923*
X05601Y0093*
X0559Y00934*
X05578Y00936*
G37*
G36*
X03979D02*
X03967Y00934D01*
X03956Y0093*
X03947Y00923*
X03939Y00913*
X03935Y00902*
X03933Y0089*
X03935Y00878*
X03939Y00867*
X03947Y00858*
X03956Y0085*
X03967Y00846*
X03979Y00844*
X03991Y00846*
X04002Y0085*
X04012Y00858*
X04019Y00867*
X04024Y00878*
X04025Y0089*
X04024Y00902*
X04019Y00913*
X04012Y00923*
X04002Y0093*
X03991Y00934*
X03979Y00936*
G37*
G36*
X00199Y0097D02*
X00187Y00969D01*
X00175Y00965*
X00164Y00959*
X00154Y00951*
X00146Y00941*
X0014Y0093*
X00136Y00918*
X00135Y00906*
X00136Y00893*
X0014Y00881*
X00146Y0087*
X00154Y0086*
X00164Y00852*
X00175Y00846*
X00187Y00842*
X00199Y00841*
X00212Y00842*
X00224Y00846*
X00235Y00852*
X00245Y0086*
X00253Y0087*
X00259Y00881*
X00262Y00893*
X00264Y00906*
X00262Y00918*
X00259Y0093*
X00253Y00941*
X00245Y00951*
X00235Y00959*
X00224Y00965*
X00212Y00969*
X00199Y0097*
G37*
G36*
X02759Y00811D02*
X02753Y0081D01*
X02748Y00806*
X02743*
X02738Y0081*
X02732Y00811*
X02726Y0081*
X0272Y00806*
X02717Y00801*
X02715Y00795*
X02717Y00789*
X0272Y00783*
X02726Y0078*
X02732Y00778*
X02738Y0078*
X02743Y00783*
X02748*
X02753Y0078*
X02759Y00778*
X02766Y0078*
X02771Y00783*
X02774Y00789*
X02776Y00795*
X02774Y00801*
X02771Y00806*
X02766Y0081*
X02759Y00811*
G37*
G36*
X02692D02*
X02686Y0081D01*
X02681Y00806*
X02676*
X02671Y0081*
X02665Y00811*
X02659Y0081*
X02653Y00806*
X0265Y00801*
X02649Y00795*
X0265Y00789*
X02653Y00783*
X02659Y0078*
X02665Y00778*
X02671Y0078*
X02676Y00783*
X02681*
X02686Y0078*
X02692Y00778*
X02699Y0078*
X02704Y00783*
X02707Y00789*
X02709Y00795*
X02707Y00801*
X02704Y00806*
X02699Y0081*
X02692Y00811*
G37*
G36*
X02625D02*
X02619Y0081D01*
X02614Y00806*
X02609*
X02604Y0081*
X02598Y00811*
X02592Y0081*
X02586Y00806*
X02583Y00801*
X02582Y00795*
X02583Y00789*
X02586Y00783*
X02592Y0078*
X02598Y00778*
X02604Y0078*
X02609Y00783*
X02614*
X02619Y0078*
X02625Y00778*
X02632Y0078*
X02637Y00783*
X02641Y00789*
X02642Y00795*
X02641Y00801*
X02637Y00806*
X02632Y0081*
X02625Y00811*
G37*
G36*
X02893D02*
X02887Y0081D01*
X02882Y00806*
X0288Y00805*
X02874*
X02873Y00806*
X02868Y0081*
X02862Y00811*
X02855Y0081*
X0285Y00806*
X02847Y00801*
X02847Y00801*
X02841*
X02841Y00801*
X02838Y00806*
X02833Y0081*
X02826Y00811*
X0282Y0081*
X02815Y00806*
X0281*
X02805Y0081*
X02799Y00811*
X02792Y0081*
X02787Y00806*
X02784Y00801*
X02782Y00795*
X02784Y00789*
X02787Y00783*
X02792Y0078*
X02799Y00778*
X02805Y0078*
X0281Y00783*
X02815*
X0282Y0078*
X02826Y00778*
X02833Y0078*
X02838Y00783*
X02841Y00789*
X02841Y00789*
X02847*
X02847Y00789*
X0285Y00783*
X02855Y0078*
X02862Y00778*
X02868Y0078*
X02873Y00783*
X02874Y00785*
X0288*
X02882Y00783*
X02887Y0078*
X02893Y00778*
X02899Y0078*
X02905Y00783*
X02908Y00789*
X0291Y00795*
X02908Y00801*
X02905Y00806*
X02899Y0081*
X02893Y00811*
G37*
G36*
X0099Y00703D02*
X00983Y00702D01*
X00978Y00698*
X00975Y00693*
X00973Y00687*
X00975Y0068*
X00978Y00675*
X00983Y00671*
X0099Y0067*
X00996Y00671*
X01001Y00675*
X01005Y0068*
X01006Y00687*
X01005Y00693*
X01001Y00698*
X00996Y00702*
X0099Y00703*
G37*
G36*
X02469Y00427D02*
X02463Y00426D01*
X02458Y00422*
X02454Y00417*
X02453Y0041*
X02454Y00404*
X02458Y00399*
X02463Y00395*
X02469Y00394*
X02476Y00395*
X02481Y00399*
X02484Y00404*
X02486Y0041*
X02484Y00417*
X02481Y00422*
X02476Y00426*
X02469Y00427*
G37*
G36*
X0298Y00425D02*
X02974Y00424D01*
X02968Y0042*
X02965Y00415*
X02964Y00409*
X02965Y00402*
X02968Y00397*
X02974Y00394*
X0298Y00392*
X02986Y00394*
X02991Y00397*
X02995Y00402*
X02996Y00409*
X02995Y00415*
X02991Y0042*
X02986Y00424*
X0298Y00425*
G37*
G36*
X03019Y00421D02*
X03013Y0042D01*
X03008Y00417*
X03004Y00411*
X03003Y00405*
X03004Y00399*
X03008Y00393*
X03013Y0039*
X03019Y00389*
X03025Y0039*
X03031Y00393*
X03034Y00399*
X03036Y00405*
X03034Y00411*
X03031Y00417*
X03025Y0042*
X03019Y00421*
G37*
G36*
X02821Y00424D02*
X02815Y00422D01*
X0281Y00419*
X02806Y00414*
X02805Y00407*
X02806Y00401*
X0281Y00396*
X02815Y00392*
X02821Y00391*
X02828Y00392*
X02833Y00396*
X02834Y00397*
X02835Y00398*
X0284Y00397*
X02842Y00393*
X02848Y0039*
X02854Y00389*
X0286Y0039*
X02865Y00393*
X02869Y00399*
X0287Y00405*
X02869Y00411*
X02865Y00417*
X0286Y0042*
X02854Y00421*
X02848Y0042*
X02842Y00417*
X02841Y00415*
X02841Y00415*
X02835Y00415*
X02833Y00419*
X02828Y00422*
X02821Y00424*
G37*
G36*
X02704Y00421D02*
X02698Y0042D01*
X02693Y00417*
X02689Y00411*
X02688Y00405*
X02689Y00399*
X02693Y00393*
X02698Y0039*
X02704Y00389*
X0271Y0039*
X02716Y00393*
X02719Y00399*
X02721Y00405*
X02719Y00411*
X02716Y00417*
X0271Y0042*
X02704Y00421*
G37*
G36*
X02665D02*
X02659Y0042D01*
X02653Y00417*
X0265Y00411*
X02649Y00405*
X0265Y00399*
X02653Y00393*
X02659Y0039*
X02665Y00389*
X02671Y0039*
X02676Y00393*
X0268Y00399*
X02681Y00405*
X0268Y00411*
X02676Y00417*
X02671Y0042*
X02665Y00421*
G37*
G36*
X02511D02*
X02505Y0042D01*
X025Y00417*
X02496Y00411*
X02495Y00405*
X02496Y00399*
X025Y00393*
X02505Y0039*
X02511Y00389*
X02518Y0039*
X02523Y00393*
X02526Y00399*
X02528Y00405*
X02526Y00411*
X02523Y00417*
X02518Y0042*
X02511Y00421*
G37*
G36*
X02389D02*
X02383Y0042D01*
X02378Y00417*
X02374Y00411*
X02373Y00405*
X02374Y00399*
X02378Y00393*
X02383Y0039*
X02389Y00389*
X02396Y0039*
X02401Y00393*
X02404Y00399*
X02406Y00405*
X02404Y00411*
X02401Y00417*
X02396Y0042*
X02389Y00421*
G37*
G36*
X0235D02*
X02344Y0042D01*
X02338Y00417*
X02335Y00411*
X02334Y00405*
X02335Y00399*
X02338Y00393*
X02344Y0039*
X0235Y00389*
X02356Y0039*
X02361Y00393*
X02365Y00399*
X02366Y00405*
X02365Y00411*
X02361Y00417*
X02356Y0042*
X0235Y00421*
G37*
G36*
X01872Y00303D02*
X01865Y00302D01*
X01862Y003*
X01858Y00302*
X01852Y00303*
X01846Y00302*
X01842Y003*
X01838Y00302*
X01832Y00303*
X01826Y00302*
X01821Y00298*
X01817Y00293*
X01816Y00287*
X01817Y00281*
X01821Y00275*
X01822Y00274*
Y00268*
X01821Y00267*
X01817Y00262*
X01816Y00255*
X01817Y00249*
X01821Y00244*
X01826Y0024*
X01832Y00239*
X01838Y0024*
X01842Y00243*
X01846Y0024*
X01852Y00239*
X01858Y0024*
X01862Y00243*
X01865Y0024*
X01872Y00239*
X01878Y0024*
X01883Y00244*
X01887Y00249*
X01888Y00255*
X01887Y00262*
X01883Y00267*
X01881Y00268*
Y00274*
X01883Y00275*
X01887Y00281*
X01888Y00287*
X01887Y00293*
X01883Y00298*
X01878Y00302*
X01872Y00303*
G37*
G36*
X00285Y00439D02*
X00271Y00437D01*
X00258Y00433*
X00246Y00427*
X00235Y00418*
X00226Y00407*
X00219Y00395*
X00215Y00381*
X00214Y00368*
X00215Y00354*
X00219Y0034*
X00226Y00328*
X00235Y00317*
X00246Y00309*
X00258Y00302*
X00271Y00298*
X00285Y00297*
X00299Y00298*
X00312Y00302*
X00324Y00309*
X00335Y00317*
X00344Y00328*
X0035Y0034*
X00355Y00354*
X00356Y00368*
X00355Y00381*
X0035Y00395*
X00344Y00407*
X00335Y00418*
X00324Y00427*
X00312Y00433*
X00299Y00437*
X00285Y00439*
G37*
G36*
X02112Y00303D02*
X02105Y00302D01*
X021Y00298*
X02097Y00293*
X02097Y00293*
X02091*
X02091Y00293*
X02088Y00298*
X02083Y00302*
X02076Y00303*
X0207Y00302*
X02065Y00298*
X02061Y00293*
X0206Y00287*
X02061Y00281*
X02065Y00275*
X02067Y00274*
Y00268*
X02065Y00267*
X02061Y00262*
X0206Y00255*
X02061Y00249*
X02065Y00244*
X0207Y0024*
X02076Y00239*
X02083Y0024*
X02088Y00244*
X02091Y00249*
X02091Y0025*
X02097*
X02097Y00249*
X021Y00244*
X02105Y0024*
X02112Y00239*
X02118Y0024*
X02123Y00244*
X02127Y00249*
X02128Y00255*
X02127Y00262*
X02123Y00267*
X02121Y00268*
Y00274*
X02123Y00275*
X02127Y00281*
X02128Y00287*
X02127Y00293*
X02123Y00298*
X02118Y00302*
X02112Y00303*
G37*
G36*
X0261Y00295D02*
X02603Y00294D01*
X02598Y00291*
X02597Y00289*
X02591*
X0259Y00291*
X02584Y00294*
X02578Y00295*
X02572Y00294*
X02567Y00291*
X02563Y00285*
X02562Y00279*
X02563Y00273*
X02567Y00267*
X02572Y00264*
X02578Y00263*
X02584Y00264*
X0259Y00267*
X02591Y00269*
X02597*
X02598Y00267*
X02603Y00264*
X0261Y00263*
X02616Y00264*
X02621Y00267*
X02625Y00273*
X02626Y00279*
X02625Y00285*
X02621Y00291*
X02616Y00294*
X0261Y00295*
G37*
G36*
X02444D02*
X02438Y00294D01*
X02433Y00291*
X02432Y00289*
X02426*
X02424Y00291*
X02419Y00294*
X02413Y00295*
X02407Y00294*
X02401Y00291*
X02398Y00285*
X02397Y00279*
X02398Y00273*
X02401Y00267*
X02407Y00264*
X02413Y00263*
X02419Y00264*
X02424Y00267*
X02426Y00269*
X02432*
X02433Y00267*
X02438Y00264*
X02444Y00263*
X02451Y00264*
X02456Y00267*
X02459Y00273*
X02461Y00279*
X02459Y00285*
X02456Y00291*
X02451Y00294*
X02444Y00295*
G37*
G36*
X02937D02*
X0293Y00294D01*
X02925Y00291*
X02924Y00289*
X02918*
X02917Y00291*
X02911Y00294*
X02905Y00295*
X02899Y00294*
X02893Y00291*
X0289Y00285*
X02889Y00279*
X0289Y00273*
X02893Y00267*
X02899Y00264*
X02905Y00263*
X02911Y00264*
X02917Y00267*
X02918Y00269*
X02924*
X02925Y00267*
X0293Y00264*
X02937Y00263*
X02943Y00264*
X02948Y00267*
X02952Y00273*
X02953Y00279*
X02952Y00285*
X02948Y00291*
X02943Y00294*
X02937Y00295*
G37*
G36*
X02748Y00298D02*
X02742Y00297D01*
X02737Y00293*
X02733Y00288*
X02732Y00282*
X02733Y00276*
X02737Y0027*
X02742Y00267*
X02748Y00266*
X02755Y00267*
X0276Y0027*
X02766Y0027*
X02767Y00267*
X02773Y00264*
X02779Y00263*
X02785Y00264*
X02791Y00267*
X02794Y00273*
X02795Y00279*
X02794Y00285*
X02791Y00291*
X02785Y00294*
X02779Y00295*
X02773Y00294*
X02767Y00291*
X02762Y00291*
X0276Y00293*
X02755Y00297*
X02748Y00298*
G37*
G36*
X02151Y00303D02*
X02145Y00302D01*
X0214Y00298*
X02136Y00293*
X02135Y00287*
X02136Y00281*
X0214Y00275*
X02141Y00274*
Y00268*
X0214Y00267*
X02136Y00262*
X02135Y00255*
X02136Y00249*
X0214Y00244*
X02145Y0024*
X02151Y00239*
X02157Y0024*
X02163Y00244*
X02166Y00249*
X02167Y00255*
X02166Y00262*
X02163Y00267*
X02161Y00268*
Y00274*
X02163Y00275*
X02166Y00281*
X02167Y00287*
X02166Y00293*
X02163Y00298*
X02157Y00302*
X02151Y00303*
G37*
%LNgrandmaster-3*%
%LPD*%
G54D143*
X00299Y01006D03*
Y00806D03*
X00099D03*
Y01006D03*
X00299Y02581D03*
Y02381D03*
X00099D03*
Y02581D03*
X00299Y02056D03*
Y01856D03*
X00099D03*
Y02056D03*
X00299Y01531D03*
Y01331D03*
X00099D03*
Y01531D03*
G54D150*
X00285Y04152D03*
Y00368D03*
G54D159*
X05127Y02307D03*
G54D161*
X05578Y01689D03*
X03979Y02489D03*
G54D162*
X069Y03589D03*
X06734D03*
X06569D03*
G54D163*
X05934Y03937D03*
G54D164*
X06119Y04056D03*
G54D171*
X02878Y00249D03*
X02957Y00251D03*
X02447Y00242D03*
X02606Y00931D03*
X02636Y00247D03*
X02799Y00251D03*
X02409Y01088D03*
X02311Y0109D03*
X02508Y00931D03*
X02409Y00932D03*
X02724Y01093D03*
X02784Y01094D03*
X02842Y01095D03*
X02546Y00244D03*
X03097Y00251D03*
X02606Y01091D03*
X03554Y01841D03*
X03719Y01996D03*
X01721Y0189D03*
X01671Y01792D03*
X01674Y01989D03*
X02508Y0109D03*
X03413Y01573D03*
X0167Y01595D03*
X02409Y02579D03*
X02586Y02569D03*
X01718Y01792D03*
X02881Y02566D03*
X03732Y01418D03*
X02253Y02279D03*
X02311Y00934D03*
X03554Y01991D03*
X01675Y01891D03*
X02783Y02429D03*
X03719Y01921D03*
X02665Y01092D03*
X02475Y02456D03*
X03414Y01805D03*
X02685Y02311D03*
X0359Y01662D03*
X02404Y02412D03*
X01716Y01399D03*
X01721Y01989D03*
X03549Y01413D03*
X02488Y02413D03*
X0167Y01694D03*
X02901Y01095D03*
X03594Y01514D03*
X03406Y01461D03*
X0341Y01713D03*
X02933Y00953D03*
X02871Y02297D03*
X02685Y02568D03*
X03554Y01941D03*
X02783Y02568D03*
X03718Y01713D03*
X01721Y01694D03*
X01671Y01399D03*
X02581Y02308D03*
X01718Y01497D03*
X01714Y01595D03*
X01671Y01497D03*
X02321Y02586D03*
X02034Y00246D03*
X01916Y00244D03*
X02309Y00246D03*
X0333Y03301D03*
X0412Y03594D03*
X03183Y03135D03*
X03277Y02963D03*
X02419Y02788D03*
X02413Y03295D03*
X02321Y03361D03*
X02631Y02876D03*
X02473Y0298D03*
X00937Y02317D03*
X01726Y04329D03*
X01788D03*
X04477Y03135D03*
X04064Y02722D03*
X06628Y01372D03*
X06974Y01939D03*
X03968Y01671D03*
X04131Y01686D03*
X03996Y01711D03*
X0396Y02724D03*
X06253Y02909D03*
X06647Y03129D03*
X04339Y02725D03*
X0383Y03762D03*
X03395Y04222D03*
X04272Y03135D03*
X02139Y03738D03*
X04208Y03135D03*
X06626Y03032D03*
X04152Y03135D03*
X02724Y03521D03*
X01248Y02D03*
X04068Y03135D03*
X02674Y03501D03*
X04234Y02725D03*
X06456Y03009D03*
X01691Y04079D03*
X03642Y00636D03*
X04039Y03784D03*
X06476Y03231D03*
X04333Y03135D03*
X01261Y02482D03*
X04114Y03135D03*
X06648Y03341D03*
X02888Y04221D03*
X0337Y02888D03*
X02258Y03741D03*
X01749Y0411D03*
X0229Y04217D03*
X0388Y03109D03*
X03744Y03342D03*
X03717Y03072D03*
X05733Y03556D03*
X05676Y03546D03*
X03603Y00682D03*
X06548Y01531D03*
X06602Y01612D03*
Y01672D03*
Y01722D03*
X06601Y01777D03*
X06685Y01828D03*
X06699Y01881D03*
X06949Y02095D03*
X06607Y02176D03*
X06395Y02111D03*
X06048Y02171D03*
X06004Y02434D03*
X06274Y02391D03*
X06398Y02453D03*
X06397Y02501D03*
X06396Y02556D03*
X06397Y0261D03*
X06398Y02657D03*
X06372Y02909D03*
X0491Y04203D03*
X04387Y04206D03*
X03777Y04023D03*
X04085Y03892D03*
X04194Y03884D03*
X04431Y03135D03*
X0286Y03787D03*
X02724Y03729D03*
X03531Y0366D03*
X03269Y03788D03*
X01242Y01472D03*
X01256Y00942D03*
X00654Y0079D03*
X00655Y01028D03*
X00654Y01314D03*
X00653Y01551D03*
X00654Y01839D03*
Y02073D03*
Y02365D03*
X00653Y02593D03*
G54D172*
X02531Y03853D03*
Y0283D03*
X00149D03*
Y03853D03*
M02*